FILE_TYPE = MACRO_DRAWING;
SET COLOR_WIRE YELLOW;
SET COLOR_PROP ORANGE;
SET COLOR_DOT WHITE;
SET COLOR_ARC YELLOW;
SET COLOR_BODY GREEN;
SET COLOR_NOTE PURPLE;
SET PROP_DISPLAY VALUE;
SET PAGE_NUMBER P22;
FORCEADD GENOA_SP5..11
(-4775 4925);
FORCEPROP 1 LAST LOCATION U25
J 0
(-5870 6181);
DISPLAY 0.489362 (-5870 6181);
PAINT SKYBLUE (-5870 6181);
FORCEPROP 0 LAST $SEC 11
J 0
(-5850 6225);
DISPLAY 0.680851 (-5850 6225);
PAINT MONO (-5850 6225);
DISPLAY INVISIBLE (-5850 6225);
FORCEPROP 0 LAST CDS_SEC 11
J 0
(-5875 6175);
DISPLAY 1.021277 (-5875 6175);
DISPLAY INVISIBLE (-5875 6175);
FORCEPROP 0 LASTPIN (-6025 5625) $PN M40
J 2
(-6035 5635);
DISPLAY 0.489362 (-6035 5635);
PAINT MONO (-6035 5635);
FORCEPROP 0 LASTPIN (-6025 5525) $PN K40
J 2
(-6035 5535);
DISPLAY 0.489362 (-6035 5535);
PAINT MONO (-6035 5535);
FORCEPROP 0 LASTPIN (-6025 5425) $PN H40
J 2
(-6035 5435);
DISPLAY 0.489362 (-6035 5435);
PAINT MONO (-6035 5435);
FORCEPROP 0 LASTPIN (-6025 5325) $PN L43
J 2
(-6035 5335);
DISPLAY 0.489362 (-6035 5335);
PAINT MONO (-6035 5335);
FORCEPROP 0 LASTPIN (-6025 5225) $PN G43
J 2
(-6035 5235);
DISPLAY 0.489362 (-6035 5235);
PAINT MONO (-6035 5235);
FORCEPROP 0 LASTPIN (-6025 5125) $PN J43
J 2
(-6035 5135);
DISPLAY 0.489362 (-6035 5135);
PAINT MONO (-6035 5135);
FORCEPROP 0 LASTPIN (-6025 5025) $PN L46
J 2
(-6035 5035);
DISPLAY 0.489362 (-6035 5035);
PAINT MONO (-6035 5035);
FORCEPROP 0 LASTPIN (-6025 4925) $PN G46
J 2
(-6035 4935);
DISPLAY 0.489362 (-6035 4935);
PAINT MONO (-6035 4935);
FORCEPROP 0 LASTPIN (-6025 4825) $PN J46
J 2
(-6035 4835);
DISPLAY 0.489362 (-6035 4835);
PAINT MONO (-6035 4835);
FORCEPROP 0 LASTPIN (-6025 4725) $PN L49
J 2
(-6035 4735);
DISPLAY 0.489362 (-6035 4735);
PAINT MONO (-6035 4735);
FORCEPROP 0 LASTPIN (-6025 4625) $PN G49
J 2
(-6035 4635);
DISPLAY 0.489362 (-6035 4635);
PAINT MONO (-6035 4635);
FORCEPROP 0 LASTPIN (-6025 4525) $PN J49
J 2
(-6035 4535);
DISPLAY 0.489362 (-6035 4535);
PAINT MONO (-6035 4535);
FORCEPROP 0 LASTPIN (-6025 4425) $PN L52
J 2
(-6035 4435);
DISPLAY 0.489362 (-6035 4435);
PAINT MONO (-6035 4435);
FORCEPROP 0 LASTPIN (-6025 4325) $PN G52
J 2
(-6035 4335);
DISPLAY 0.489362 (-6035 4335);
PAINT MONO (-6035 4335);
FORCEPROP 0 LASTPIN (-6025 4225) $PN J52
J 2
(-6035 4235);
DISPLAY 0.489362 (-6035 4235);
PAINT MONO (-6035 4235);
FORCEPROP 0 LASTPIN (-6025 4125) $PN N52
J 2
(-6035 4135);
DISPLAY 0.489362 (-6035 4135);
PAINT MONO (-6035 4135);
FORCEPROP 0 LASTPIN (-6025 5675) $PN M41
J 2
(-6035 5685);
DISPLAY 0.489362 (-6035 5685);
PAINT MONO (-6035 5685);
FORCEPROP 0 LASTPIN (-6025 5575) $PN K41
J 2
(-6035 5585);
DISPLAY 0.489362 (-6035 5585);
PAINT MONO (-6035 5585);
FORCEPROP 0 LASTPIN (-6025 5475) $PN H41
J 2
(-6035 5485);
DISPLAY 0.489362 (-6035 5485);
PAINT MONO (-6035 5485);
FORCEPROP 0 LASTPIN (-6025 5375) $PN L44
J 2
(-6035 5385);
DISPLAY 0.489362 (-6035 5385);
PAINT MONO (-6035 5385);
FORCEPROP 0 LASTPIN (-6025 5275) $PN G44
J 2
(-6035 5285);
DISPLAY 0.489362 (-6035 5285);
PAINT MONO (-6035 5285);
FORCEPROP 0 LASTPIN (-6025 5175) $PN J44
J 2
(-6035 5185);
DISPLAY 0.489362 (-6035 5185);
PAINT MONO (-6035 5185);
FORCEPROP 0 LASTPIN (-6025 5075) $PN L47
J 2
(-6035 5085);
DISPLAY 0.489362 (-6035 5085);
PAINT MONO (-6035 5085);
FORCEPROP 0 LASTPIN (-6025 4975) $PN G47
J 2
(-6035 4985);
DISPLAY 0.489362 (-6035 4985);
PAINT MONO (-6035 4985);
FORCEPROP 0 LASTPIN (-6025 4875) $PN J47
J 2
(-6035 4885);
DISPLAY 0.489362 (-6035 4885);
PAINT MONO (-6035 4885);
FORCEPROP 0 LASTPIN (-6025 4775) $PN L50
J 2
(-6035 4785);
DISPLAY 0.489362 (-6035 4785);
PAINT MONO (-6035 4785);
FORCEPROP 0 LASTPIN (-6025 4675) $PN G50
J 2
(-6035 4685);
DISPLAY 0.489362 (-6035 4685);
PAINT MONO (-6035 4685);
FORCEPROP 0 LASTPIN (-6025 4575) $PN J50
J 2
(-6035 4585);
DISPLAY 0.489362 (-6035 4585);
PAINT MONO (-6035 4585);
FORCEPROP 0 LASTPIN (-6025 4475) $PN L53
J 2
(-6035 4485);
DISPLAY 0.489362 (-6035 4485);
PAINT MONO (-6035 4485);
FORCEPROP 0 LASTPIN (-6025 4375) $PN G53
J 2
(-6035 4385);
DISPLAY 0.489362 (-6035 4385);
PAINT MONO (-6035 4385);
FORCEPROP 0 LASTPIN (-6025 4275) $PN J53
J 2
(-6035 4285);
DISPLAY 0.489362 (-6035 4285);
PAINT MONO (-6035 4285);
FORCEPROP 0 LASTPIN (-6025 4175) $PN N53
J 2
(-6035 4185);
DISPLAY 0.489362 (-6035 4185);
PAINT MONO (-6035 4185);
FORCEPROP 0 LASTPIN (-3525 5625) $PN AF41
J 0
(-3515 5635);
DISPLAY 0.489362 (-3515 5635);
PAINT MONO (-3515 5635);
FORCEPROP 0 LASTPIN (-3525 5525) $PN AD41
J 0
(-3515 5535);
DISPLAY 0.489362 (-3515 5535);
PAINT MONO (-3515 5535);
FORCEPROP 0 LASTPIN (-3525 5425) $PN AB41
J 0
(-3515 5435);
DISPLAY 0.489362 (-3515 5435);
PAINT MONO (-3515 5435);
FORCEPROP 0 LASTPIN (-3525 5325) $PN AG44
J 0
(-3515 5335);
DISPLAY 0.489362 (-3515 5335);
PAINT MONO (-3515 5335);
FORCEPROP 0 LASTPIN (-3525 5225) $PN AA44
J 0
(-3515 5235);
DISPLAY 0.489362 (-3515 5235);
PAINT MONO (-3515 5235);
FORCEPROP 0 LASTPIN (-3525 5125) $PN AC44
J 0
(-3515 5135);
DISPLAY 0.489362 (-3515 5135);
PAINT MONO (-3515 5135);
FORCEPROP 0 LASTPIN (-3525 5025) $PN AE44
J 0
(-3515 5035);
DISPLAY 0.489362 (-3515 5035);
PAINT MONO (-3515 5035);
FORCEPROP 0 LASTPIN (-3525 4925) $PN AG47
J 0
(-3515 4935);
DISPLAY 0.489362 (-3515 4935);
PAINT MONO (-3515 4935);
FORCEPROP 0 LASTPIN (-3525 4825) $PN AC47
J 0
(-3515 4835);
DISPLAY 0.489362 (-3515 4835);
PAINT MONO (-3515 4835);
FORCEPROP 0 LASTPIN (-3525 4725) $PN AE47
J 0
(-3515 4735);
DISPLAY 0.489362 (-3515 4735);
PAINT MONO (-3515 4735);
FORCEPROP 0 LASTPIN (-3525 4625) $PN AG50
J 0
(-3515 4635);
DISPLAY 0.489362 (-3515 4635);
PAINT MONO (-3515 4635);
FORCEPROP 0 LASTPIN (-3525 4525) $PN AC50
J 0
(-3515 4535);
DISPLAY 0.489362 (-3515 4535);
PAINT MONO (-3515 4535);
FORCEPROP 0 LASTPIN (-3525 4425) $PN AE50
J 0
(-3515 4435);
DISPLAY 0.489362 (-3515 4435);
PAINT MONO (-3515 4435);
FORCEPROP 0 LASTPIN (-3525 4325) $PN AG53
J 0
(-3515 4335);
DISPLAY 0.489362 (-3515 4335);
PAINT MONO (-3515 4335);
FORCEPROP 0 LASTPIN (-3525 4225) $PN AC53
J 0
(-3515 4235);
DISPLAY 0.489362 (-3515 4235);
PAINT MONO (-3515 4235);
FORCEPROP 0 LASTPIN (-3525 4125) $PN AE53
J 0
(-3515 4135);
DISPLAY 0.489362 (-3515 4135);
PAINT MONO (-3515 4135);
FORCEPROP 0 LASTPIN (-3525 5675) $PN AF40
J 0
(-3515 5685);
DISPLAY 0.489362 (-3515 5685);
PAINT MONO (-3515 5685);
FORCEPROP 0 LASTPIN (-3525 5575) $PN AD40
J 0
(-3515 5585);
DISPLAY 0.489362 (-3515 5585);
PAINT MONO (-3515 5585);
FORCEPROP 0 LASTPIN (-3525 5475) $PN AB40
J 0
(-3515 5485);
DISPLAY 0.489362 (-3515 5485);
PAINT MONO (-3515 5485);
FORCEPROP 0 LASTPIN (-3525 5375) $PN AG43
J 0
(-3515 5385);
DISPLAY 0.489362 (-3515 5385);
PAINT MONO (-3515 5385);
FORCEPROP 0 LASTPIN (-3525 5275) $PN AA43
J 0
(-3515 5285);
DISPLAY 0.489362 (-3515 5285);
PAINT MONO (-3515 5285);
FORCEPROP 0 LASTPIN (-3525 5175) $PN AC43
J 0
(-3515 5185);
DISPLAY 0.489362 (-3515 5185);
PAINT MONO (-3515 5185);
FORCEPROP 0 LASTPIN (-3525 5075) $PN AE43
J 0
(-3515 5085);
DISPLAY 0.489362 (-3515 5085);
PAINT MONO (-3515 5085);
FORCEPROP 0 LASTPIN (-3525 4975) $PN AG46
J 0
(-3515 4985);
DISPLAY 0.489362 (-3515 4985);
PAINT MONO (-3515 4985);
FORCEPROP 0 LASTPIN (-3525 4875) $PN AC46
J 0
(-3515 4885);
DISPLAY 0.489362 (-3515 4885);
PAINT MONO (-3515 4885);
FORCEPROP 0 LASTPIN (-3525 4775) $PN AE46
J 0
(-3515 4785);
DISPLAY 0.489362 (-3515 4785);
PAINT MONO (-3515 4785);
FORCEPROP 0 LASTPIN (-3525 4675) $PN AG49
J 0
(-3515 4685);
DISPLAY 0.489362 (-3515 4685);
PAINT MONO (-3515 4685);
FORCEPROP 0 LASTPIN (-3525 4575) $PN AC49
J 0
(-3515 4585);
DISPLAY 0.489362 (-3515 4585);
PAINT MONO (-3515 4585);
FORCEPROP 0 LASTPIN (-3525 4475) $PN AE49
J 0
(-3515 4485);
DISPLAY 0.489362 (-3515 4485);
PAINT MONO (-3515 4485);
FORCEPROP 0 LASTPIN (-3525 4375) $PN AG52
J 0
(-3515 4385);
DISPLAY 0.489362 (-3515 4385);
PAINT MONO (-3515 4385);
FORCEPROP 0 LASTPIN (-3525 4275) $PN AC52
J 0
(-3515 4285);
DISPLAY 0.489362 (-3515 4285);
PAINT MONO (-3515 4285);
FORCEPROP 0 LASTPIN (-3525 4175) $PN AE52
J 0
(-3515 4185);
DISPLAY 0.489362 (-3515 4185);
PAINT MONO (-3515 4185);
FORCEPROP 2 LAST PART_TYPE SMLF
J 0
(-5875 6103);
DISPLAY 1.021277 (-5875 6103);
FORCEPROP 1 LAST MATERIAL IO
J 0
(-5870 5907);
DISPLAY 0.489362 (-5870 5907);
PAINT SKYBLUE (-5870 5907);
FORCEPROP 2 LAST VALUE SOCKET6096_13568-001
J 0
(-5875 6003);
DISPLAY 0.489362 (-5875 6003);
PAINT SKYBLUE (-5875 6003);
FORCEPROP 1 LAST PART_NUMBER DGA^6000030
J 0
(-5870 6034);
DISPLAY 0.489362 (-5870 6034);
PAINT SKYBLUE (-5870 6034);
FORCEPROP 2 LAST CDS_LIB pure_quanta
J 0
(-4775 4925);
DISPLAY INVISIBLE (-4775 4925);
FORCEPROP 1 LAST NEEDS_NO_SIZE TRUE
J 0
(-4775 4925);
DISPLAY 0.723404 (-4775 4925);
PAINT GREEN (-4775 4925);
DISPLAY INVISIBLE (-4775 4925);
FORCEPROP 1 LAST CDS_LMAN_SYM_OUTLINE -1100,950,1100,-950
J 0
(-4775 4925);
DISPLAY 0.468085 (-4775 4925);
PAINT GREEN (-4775 4925);
DISPLAY INVISIBLE (-4775 4925);
FORCEPROP 1 LAST PATH I207
J 0
(-4775 4925);
DISPLAY 0.723404 (-4775 4925);
PAINT GREEN (-4775 4925);
DISPLAY INVISIBLE (-4775 4925);
FORCEADD GENOA_SP5..12
(-4775 2200);
FORCEPROP 1 LAST LOCATION U25
J 0
(-5870 3456);
DISPLAY 0.489362 (-5870 3456);
PAINT SKYBLUE (-5870 3456);
FORCEPROP 0 LAST $SEC 12
J 0
(-5850 3500);
DISPLAY 0.680851 (-5850 3500);
PAINT MONO (-5850 3500);
DISPLAY INVISIBLE (-5850 3500);
FORCEPROP 0 LAST CDS_SEC 12
J 0
(-5875 3400);
DISPLAY 1.021277 (-5875 3400);
DISPLAY INVISIBLE (-5875 3400);
FORCEPROP 0 LASTPIN (-6025 2900) $PN V40
J 2
(-6035 2910);
DISPLAY 0.489362 (-6035 2910);
PAINT MONO (-6035 2910);
FORCEPROP 0 LASTPIN (-6025 2800) $PN T40
J 2
(-6035 2810);
DISPLAY 0.489362 (-6035 2810);
PAINT MONO (-6035 2810);
FORCEPROP 0 LASTPIN (-6025 2700) $PN P40
J 2
(-6035 2710);
DISPLAY 0.489362 (-6035 2710);
PAINT MONO (-6035 2710);
FORCEPROP 0 LASTPIN (-6025 2600) $PN U43
J 2
(-6035 2610);
DISPLAY 0.489362 (-6035 2610);
PAINT MONO (-6035 2610);
FORCEPROP 0 LASTPIN (-6025 2500) $PN N43
J 2
(-6035 2510);
DISPLAY 0.489362 (-6035 2510);
PAINT MONO (-6035 2510);
FORCEPROP 0 LASTPIN (-6025 2400) $PN R43
J 2
(-6035 2410);
DISPLAY 0.489362 (-6035 2410);
PAINT MONO (-6035 2410);
FORCEPROP 0 LASTPIN (-6025 2300) $PN U46
J 2
(-6035 2310);
DISPLAY 0.489362 (-6035 2310);
PAINT MONO (-6035 2310);
FORCEPROP 0 LASTPIN (-6025 2200) $PN N46
J 2
(-6035 2210);
DISPLAY 0.489362 (-6035 2210);
PAINT MONO (-6035 2210);
FORCEPROP 0 LASTPIN (-6025 2100) $PN R46
J 2
(-6035 2110);
DISPLAY 0.489362 (-6035 2110);
PAINT MONO (-6035 2110);
FORCEPROP 0 LASTPIN (-6025 2000) $PN W49
J 2
(-6035 2010);
DISPLAY 0.489362 (-6035 2010);
PAINT MONO (-6035 2010);
FORCEPROP 0 LASTPIN (-6025 1900) $PN N49
J 2
(-6035 1910);
DISPLAY 0.489362 (-6035 1910);
PAINT MONO (-6035 1910);
FORCEPROP 0 LASTPIN (-6025 1800) $PN R49
J 2
(-6035 1810);
DISPLAY 0.489362 (-6035 1810);
PAINT MONO (-6035 1810);
FORCEPROP 0 LASTPIN (-6025 1700) $PN U49
J 2
(-6035 1710);
DISPLAY 0.489362 (-6035 1710);
PAINT MONO (-6035 1710);
FORCEPROP 0 LASTPIN (-6025 1600) $PN W52
J 2
(-6035 1610);
DISPLAY 0.489362 (-6035 1610);
PAINT MONO (-6035 1610);
FORCEPROP 0 LASTPIN (-6025 1500) $PN R52
J 2
(-6035 1510);
DISPLAY 0.489362 (-6035 1510);
PAINT MONO (-6035 1510);
FORCEPROP 0 LASTPIN (-6025 1400) $PN U52
J 2
(-6035 1410);
DISPLAY 0.489362 (-6035 1410);
PAINT MONO (-6035 1410);
FORCEPROP 0 LASTPIN (-6025 2950) $PN V41
J 2
(-6035 2960);
DISPLAY 0.489362 (-6035 2960);
PAINT MONO (-6035 2960);
FORCEPROP 0 LASTPIN (-6025 2850) $PN T41
J 2
(-6035 2860);
DISPLAY 0.489362 (-6035 2860);
PAINT MONO (-6035 2860);
FORCEPROP 0 LASTPIN (-6025 2750) $PN P41
J 2
(-6035 2760);
DISPLAY 0.489362 (-6035 2760);
PAINT MONO (-6035 2760);
FORCEPROP 0 LASTPIN (-6025 2650) $PN U44
J 2
(-6035 2660);
DISPLAY 0.489362 (-6035 2660);
PAINT MONO (-6035 2660);
FORCEPROP 0 LASTPIN (-6025 2550) $PN N44
J 2
(-6035 2560);
DISPLAY 0.489362 (-6035 2560);
PAINT MONO (-6035 2560);
FORCEPROP 0 LASTPIN (-6025 2450) $PN R44
J 2
(-6035 2460);
DISPLAY 0.489362 (-6035 2460);
PAINT MONO (-6035 2460);
FORCEPROP 0 LASTPIN (-6025 2350) $PN U47
J 2
(-6035 2360);
DISPLAY 0.489362 (-6035 2360);
PAINT MONO (-6035 2360);
FORCEPROP 0 LASTPIN (-6025 2250) $PN N47
J 2
(-6035 2260);
DISPLAY 0.489362 (-6035 2260);
PAINT MONO (-6035 2260);
FORCEPROP 0 LASTPIN (-6025 2150) $PN R47
J 2
(-6035 2160);
DISPLAY 0.489362 (-6035 2160);
PAINT MONO (-6035 2160);
FORCEPROP 0 LASTPIN (-6025 2050) $PN W50
J 2
(-6035 2060);
DISPLAY 0.489362 (-6035 2060);
PAINT MONO (-6035 2060);
FORCEPROP 0 LASTPIN (-6025 1950) $PN N50
J 2
(-6035 1960);
DISPLAY 0.489362 (-6035 1960);
PAINT MONO (-6035 1960);
FORCEPROP 0 LASTPIN (-6025 1850) $PN R50
J 2
(-6035 1860);
DISPLAY 0.489362 (-6035 1860);
PAINT MONO (-6035 1860);
FORCEPROP 0 LASTPIN (-6025 1750) $PN U50
J 2
(-6035 1760);
DISPLAY 0.489362 (-6035 1760);
PAINT MONO (-6035 1760);
FORCEPROP 0 LASTPIN (-6025 1650) $PN W53
J 2
(-6035 1660);
DISPLAY 0.489362 (-6035 1660);
PAINT MONO (-6035 1660);
FORCEPROP 0 LASTPIN (-6025 1550) $PN R53
J 2
(-6035 1560);
DISPLAY 0.489362 (-6035 1560);
PAINT MONO (-6035 1560);
FORCEPROP 0 LASTPIN (-6025 1450) $PN U53
J 2
(-6035 1460);
DISPLAY 0.489362 (-6035 1460);
PAINT MONO (-6035 1460);
FORCEPROP 0 LASTPIN (-3525 2900) $PN AP41
J 0
(-3515 2910);
DISPLAY 0.489362 (-3515 2910);
PAINT MONO (-3515 2910);
FORCEPROP 0 LASTPIN (-3525 2800) $PN AM41
J 0
(-3515 2810);
DISPLAY 0.489362 (-3515 2810);
PAINT MONO (-3515 2810);
FORCEPROP 0 LASTPIN (-3525 2700) $PN AH41
J 0
(-3515 2710);
DISPLAY 0.489362 (-3515 2710);
PAINT MONO (-3515 2710);
FORCEPROP 0 LASTPIN (-3525 2600) $PN AK41
J 0
(-3515 2610);
DISPLAY 0.489362 (-3515 2610);
PAINT MONO (-3515 2610);
FORCEPROP 0 LASTPIN (-3525 2500) $PN AN44
J 0
(-3515 2510);
DISPLAY 0.489362 (-3515 2510);
PAINT MONO (-3515 2510);
FORCEPROP 0 LASTPIN (-3525 2400) $PN AJ44
J 0
(-3515 2410);
DISPLAY 0.489362 (-3515 2410);
PAINT MONO (-3515 2410);
FORCEPROP 0 LASTPIN (-3525 2300) $PN AL44
J 0
(-3515 2310);
DISPLAY 0.489362 (-3515 2310);
PAINT MONO (-3515 2310);
FORCEPROP 0 LASTPIN (-3525 2200) $PN AN47
J 0
(-3515 2210);
DISPLAY 0.489362 (-3515 2210);
PAINT MONO (-3515 2210);
FORCEPROP 0 LASTPIN (-3525 2100) $PN AJ47
J 0
(-3515 2110);
DISPLAY 0.489362 (-3515 2110);
PAINT MONO (-3515 2110);
FORCEPROP 0 LASTPIN (-3525 2000) $PN AL47
J 0
(-3515 2010);
DISPLAY 0.489362 (-3515 2010);
PAINT MONO (-3515 2010);
FORCEPROP 0 LASTPIN (-3525 1900) $PN AN50
J 0
(-3515 1910);
DISPLAY 0.489362 (-3515 1910);
PAINT MONO (-3515 1910);
FORCEPROP 0 LASTPIN (-3525 1800) $PN AJ50
J 0
(-3515 1810);
DISPLAY 0.489362 (-3515 1810);
PAINT MONO (-3515 1810);
FORCEPROP 0 LASTPIN (-3525 1700) $PN AL50
J 0
(-3515 1710);
DISPLAY 0.489362 (-3515 1710);
PAINT MONO (-3515 1710);
FORCEPROP 0 LASTPIN (-3525 1600) $PN AN53
J 0
(-3515 1610);
DISPLAY 0.489362 (-3515 1610);
PAINT MONO (-3515 1610);
FORCEPROP 0 LASTPIN (-3525 1500) $PN AJ53
J 0
(-3515 1510);
DISPLAY 0.489362 (-3515 1510);
PAINT MONO (-3515 1510);
FORCEPROP 0 LASTPIN (-3525 1400) $PN AL53
J 0
(-3515 1410);
DISPLAY 0.489362 (-3515 1410);
PAINT MONO (-3515 1410);
FORCEPROP 0 LASTPIN (-3525 2950) $PN AP40
J 0
(-3515 2960);
DISPLAY 0.489362 (-3515 2960);
PAINT MONO (-3515 2960);
FORCEPROP 0 LASTPIN (-3525 2850) $PN AM40
J 0
(-3515 2860);
DISPLAY 0.489362 (-3515 2860);
PAINT MONO (-3515 2860);
FORCEPROP 0 LASTPIN (-3525 2750) $PN AH40
J 0
(-3515 2760);
DISPLAY 0.489362 (-3515 2760);
PAINT MONO (-3515 2760);
FORCEPROP 0 LASTPIN (-3525 2650) $PN AK40
J 0
(-3515 2660);
DISPLAY 0.489362 (-3515 2660);
PAINT MONO (-3515 2660);
FORCEPROP 0 LASTPIN (-3525 2550) $PN AN43
J 0
(-3515 2560);
DISPLAY 0.489362 (-3515 2560);
PAINT MONO (-3515 2560);
FORCEPROP 0 LASTPIN (-3525 2450) $PN AJ43
J 0
(-3515 2460);
DISPLAY 0.489362 (-3515 2460);
PAINT MONO (-3515 2460);
FORCEPROP 0 LASTPIN (-3525 2350) $PN AL43
J 0
(-3515 2360);
DISPLAY 0.489362 (-3515 2360);
PAINT MONO (-3515 2360);
FORCEPROP 0 LASTPIN (-3525 2250) $PN AN46
J 0
(-3515 2260);
DISPLAY 0.489362 (-3515 2260);
PAINT MONO (-3515 2260);
FORCEPROP 0 LASTPIN (-3525 2150) $PN AJ46
J 0
(-3515 2160);
DISPLAY 0.489362 (-3515 2160);
PAINT MONO (-3515 2160);
FORCEPROP 0 LASTPIN (-3525 2050) $PN AL46
J 0
(-3515 2060);
DISPLAY 0.489362 (-3515 2060);
PAINT MONO (-3515 2060);
FORCEPROP 0 LASTPIN (-3525 1950) $PN AN49
J 0
(-3515 1960);
DISPLAY 0.489362 (-3515 1960);
PAINT MONO (-3515 1960);
FORCEPROP 0 LASTPIN (-3525 1850) $PN AJ49
J 0
(-3515 1860);
DISPLAY 0.489362 (-3515 1860);
PAINT MONO (-3515 1860);
FORCEPROP 0 LASTPIN (-3525 1750) $PN AL49
J 0
(-3515 1760);
DISPLAY 0.489362 (-3515 1760);
PAINT MONO (-3515 1760);
FORCEPROP 0 LASTPIN (-3525 1650) $PN AN52
J 0
(-3515 1660);
DISPLAY 0.489362 (-3515 1660);
PAINT MONO (-3515 1660);
FORCEPROP 0 LASTPIN (-3525 1550) $PN AJ52
J 0
(-3515 1560);
DISPLAY 0.489362 (-3515 1560);
PAINT MONO (-3515 1560);
FORCEPROP 0 LASTPIN (-3525 1450) $PN AL52
J 0
(-3515 1460);
DISPLAY 0.489362 (-3515 1460);
PAINT MONO (-3515 1460);
FORCEPROP 2 LAST PART_TYPE SMLF
J 0
(-5875 3350);
DISPLAY 1.021277 (-5875 3350);
FORCEPROP 1 LAST MATERIAL IO
J 0
(-5870 3182);
DISPLAY 0.489362 (-5870 3182);
PAINT SKYBLUE (-5870 3182);
FORCEPROP 2 LAST VALUE SOCKET6096_13568-001
J 0
(-5875 3250);
DISPLAY 0.489362 (-5875 3250);
PAINT SKYBLUE (-5875 3250);
FORCEPROP 1 LAST PART_NUMBER DGA^6000030
J 0
(-5870 3309);
DISPLAY 0.489362 (-5870 3309);
PAINT SKYBLUE (-5870 3309);
FORCEPROP 2 LAST CDS_LIB pure_quanta
J 0
(-4775 2200);
DISPLAY INVISIBLE (-4775 2200);
FORCEPROP 1 LAST NEEDS_NO_SIZE TRUE
J 0
(-4775 2200);
DISPLAY 0.723404 (-4775 2200);
PAINT GREEN (-4775 2200);
DISPLAY INVISIBLE (-4775 2200);
FORCEPROP 1 LAST CDS_LMAN_SYM_OUTLINE -1100,950,1100,-950
J 0
(-4775 2200);
DISPLAY 0.468085 (-4775 2200);
PAINT GREEN (-4775 2200);
DISPLAY INVISIBLE (-4775 2200);
FORCEPROP 1 LAST PATH I208
J 0
(-4775 2200);
DISPLAY 0.723404 (-4775 2200);
PAINT GREEN (-4775 2200);
DISPLAY INVISIBLE (-4775 2200);
FORCEADD OFFPAGE..2
(-1825 5900);
FORCEPROP 2 LAST $XR0 50 
J 0
(-1636 5900);
DISPLAY 0.638298 (-1636 5900);
PAINT MONO (-1636 5900);
FORCEPROP 2 LAST CDS_LIB standard
J 0
(-1825 5900);
DISPLAY INVISIBLE (-1825 5900);
FORCEPROP 1 LAST OFFPAGE TRUE
J 0
(-1500 5775);
DISPLAY 0.872340 (-1500 5775);
PAINT GREEN (-1500 5775);
DISPLAY INVISIBLE (-1500 5775);
FORCEPROP 1 LAST COMMENT_BODY TRUE
J 0
(-1870 5805);
DISPLAY 0.872340 (-1870 5805);
PAINT GREEN (-1870 5805);
DISPLAY INVISIBLE (-1870 5805);
FORCEPROP 2 LAST PATH I243
J 0
(-1625 5950);
DISPLAY 1.021277 (-1625 5950);
DISPLAY INVISIBLE (-1625 5950);
FORCEADD OFFPAGE..2
(-1825 5850);
FORCEPROP 2 LAST $XR0 50 
J 0
(-1636 5850);
DISPLAY 0.638298 (-1636 5850);
PAINT MONO (-1636 5850);
FORCEPROP 2 LAST CDS_LIB standard
J 0
(-1825 5850);
DISPLAY INVISIBLE (-1825 5850);
FORCEPROP 1 LAST OFFPAGE TRUE
J 0
(-1500 5725);
DISPLAY 0.872340 (-1500 5725);
PAINT GREEN (-1500 5725);
DISPLAY INVISIBLE (-1500 5725);
FORCEPROP 1 LAST COMMENT_BODY TRUE
J 0
(-1870 5755);
DISPLAY 0.872340 (-1870 5755);
PAINT GREEN (-1870 5755);
DISPLAY INVISIBLE (-1870 5755);
FORCEPROP 2 LAST PATH I244
J 0
(-1625 5900);
DISPLAY 1.021277 (-1625 5900);
DISPLAY INVISIBLE (-1625 5900);
FORCEADD TAP..6
R 2
(-3100 5675);
FORCEPROP 3 LASTPIN (-3150 5675) SIG_NAME GMI_CPU0_G0_CPU1_G2_TX_DP<0>
J 0
(-3140 5685);
DISPLAY 0.659574 (-3140 5685);
PAINT MONO (-3140 5685);
DISPLAY INVISIBLE (-3140 5685);
FORCEPROP 1 LASTPIN (-3150 5675) BN 0
J 2
(-3098 5683);
DISPLAY 0.489362 (-3098 5683);
PAINT MONO (-3098 5683);
FORCEPROP 2 LAST BOM_COST IO_SLOT
J 0
(-3600 5775);
DISPLAY 0.829787 (-3600 5775);
DISPLAY INVISIBLE (-3600 5775);
FORCEPROP 2 LAST CDS_LIB mstr_standard
J 0
(-3100 5675);
DISPLAY INVISIBLE (-3100 5675);
FORCEPROP 1 LAST BODY_TYPE PLUMBING
J 2
(-3100 5625);
DISPLAY 0.702128 (-3100 5625);
PAINT GREEN (-3100 5625);
DISPLAY INVISIBLE (-3100 5625);
FORCEPROP 1 LAST HDL_TAP TRUE
J 2
(-3425 5550);
DISPLAY 0.702128 (-3425 5550);
PAINT GREEN (-3425 5550);
DISPLAY INVISIBLE (-3425 5550);
FORCEPROP 1 LAST PATH I245
J 2
(-3098 5675);
DISPLAY 0.872340 (-3098 5675);
PAINT GREEN (-3098 5675);
DISPLAY INVISIBLE (-3098 5675);
FORCEPROP 2 LAST ROOM RISER1
J 0
(-3600 5725);
DISPLAY 0.829787 (-3600 5725);
PAINT RED (-3600 5725);
DISPLAY INVISIBLE (-3600 5725);
FORCEADD TAP..6
R 2
(-2950 5625);
FORCEPROP 3 LASTPIN (-3000 5625) SIG_NAME GMI_CPU0_G0_CPU1_G2_TX_DN<0>
J 0
(-2990 5635);
DISPLAY 0.659574 (-2990 5635);
PAINT MONO (-2990 5635);
DISPLAY INVISIBLE (-2990 5635);
FORCEPROP 1 LASTPIN (-3000 5625) BN 0
J 2
(-2948 5633);
DISPLAY 0.489362 (-2948 5633);
PAINT MONO (-2948 5633);
FORCEPROP 2 LAST BOM_COST IO_SLOT
J 0
(-3450 5725);
DISPLAY 0.829787 (-3450 5725);
DISPLAY INVISIBLE (-3450 5725);
FORCEPROP 2 LAST CDS_LIB mstr_standard
J 0
(-2950 5625);
DISPLAY INVISIBLE (-2950 5625);
FORCEPROP 1 LAST BODY_TYPE PLUMBING
J 2
(-2950 5575);
DISPLAY 0.702128 (-2950 5575);
PAINT GREEN (-2950 5575);
DISPLAY INVISIBLE (-2950 5575);
FORCEPROP 1 LAST HDL_TAP TRUE
J 2
(-3275 5500);
DISPLAY 0.702128 (-3275 5500);
PAINT GREEN (-3275 5500);
DISPLAY INVISIBLE (-3275 5500);
FORCEPROP 1 LAST PATH I246
J 2
(-2948 5625);
DISPLAY 0.872340 (-2948 5625);
PAINT GREEN (-2948 5625);
DISPLAY INVISIBLE (-2948 5625);
FORCEPROP 2 LAST ROOM RISER1
J 0
(-3450 5675);
DISPLAY 0.829787 (-3450 5675);
PAINT RED (-3450 5675);
DISPLAY INVISIBLE (-3450 5675);
FORCEADD TAP..6
R 2
(-2950 5525);
FORCEPROP 3 LASTPIN (-3000 5525) SIG_NAME GMI_CPU0_G0_CPU1_G2_TX_DN<1>
J 0
(-2990 5535);
DISPLAY 0.659574 (-2990 5535);
PAINT MONO (-2990 5535);
DISPLAY INVISIBLE (-2990 5535);
FORCEPROP 1 LASTPIN (-3000 5525) BN 1
J 2
(-2948 5533);
DISPLAY 0.489362 (-2948 5533);
PAINT MONO (-2948 5533);
FORCEPROP 2 LAST BOM_COST IO_SLOT
J 0
(-3450 5625);
DISPLAY 0.829787 (-3450 5625);
DISPLAY INVISIBLE (-3450 5625);
FORCEPROP 2 LAST CDS_LIB mstr_standard
J 0
(-2950 5525);
DISPLAY INVISIBLE (-2950 5525);
FORCEPROP 1 LAST BODY_TYPE PLUMBING
J 2
(-2950 5475);
DISPLAY 0.702128 (-2950 5475);
PAINT GREEN (-2950 5475);
DISPLAY INVISIBLE (-2950 5475);
FORCEPROP 1 LAST HDL_TAP TRUE
J 2
(-3275 5400);
DISPLAY 0.702128 (-3275 5400);
PAINT GREEN (-3275 5400);
DISPLAY INVISIBLE (-3275 5400);
FORCEPROP 1 LAST PATH I247
J 2
(-2948 5525);
DISPLAY 0.872340 (-2948 5525);
PAINT GREEN (-2948 5525);
DISPLAY INVISIBLE (-2948 5525);
FORCEPROP 2 LAST ROOM RISER1
J 0
(-3450 5575);
DISPLAY 0.829787 (-3450 5575);
PAINT RED (-3450 5575);
DISPLAY INVISIBLE (-3450 5575);
FORCEADD TAP..6
R 2
(-2950 5425);
FORCEPROP 3 LASTPIN (-3000 5425) SIG_NAME GMI_CPU0_G0_CPU1_G2_TX_DN<2>
J 0
(-2990 5435);
DISPLAY 0.659574 (-2990 5435);
PAINT MONO (-2990 5435);
DISPLAY INVISIBLE (-2990 5435);
FORCEPROP 1 LASTPIN (-3000 5425) BN 2
J 2
(-2948 5433);
DISPLAY 0.489362 (-2948 5433);
PAINT MONO (-2948 5433);
FORCEPROP 2 LAST CDS_LIB standard
J 0
(-2950 5425);
DISPLAY INVISIBLE (-2950 5425);
FORCEPROP 2 LAST BOM_COST IO_SLOT
J 0
(-3450 5525);
DISPLAY 0.829787 (-3450 5525);
DISPLAY INVISIBLE (-3450 5525);
FORCEPROP 1 LAST BODY_TYPE PLUMBING
J 2
(-2950 5375);
DISPLAY 0.702128 (-2950 5375);
PAINT GREEN (-2950 5375);
DISPLAY INVISIBLE (-2950 5375);
FORCEPROP 1 LAST HDL_TAP TRUE
J 2
(-3275 5300);
DISPLAY 0.702128 (-3275 5300);
PAINT GREEN (-3275 5300);
DISPLAY INVISIBLE (-3275 5300);
FORCEPROP 1 LAST PATH I248
J 2
(-2948 5425);
DISPLAY 0.872340 (-2948 5425);
PAINT GREEN (-2948 5425);
DISPLAY INVISIBLE (-2948 5425);
FORCEPROP 2 LAST ROOM RISER1
J 0
(-3450 5475);
DISPLAY 0.829787 (-3450 5475);
PAINT RED (-3450 5475);
DISPLAY INVISIBLE (-3450 5475);
FORCEADD TAP..6
R 2
(-3100 5475);
FORCEPROP 3 LASTPIN (-3150 5475) SIG_NAME GMI_CPU0_G0_CPU1_G2_TX_DP<2>
J 0
(-3140 5485);
DISPLAY 0.659574 (-3140 5485);
PAINT MONO (-3140 5485);
DISPLAY INVISIBLE (-3140 5485);
FORCEPROP 1 LASTPIN (-3150 5475) BN 2
J 2
(-3098 5483);
DISPLAY 0.489362 (-3098 5483);
PAINT MONO (-3098 5483);
FORCEPROP 2 LAST CDS_LIB standard
J 0
(-3100 5475);
DISPLAY INVISIBLE (-3100 5475);
FORCEPROP 2 LAST BOM_COST IO_SLOT
J 0
(-3600 5575);
DISPLAY 0.829787 (-3600 5575);
DISPLAY INVISIBLE (-3600 5575);
FORCEPROP 1 LAST BODY_TYPE PLUMBING
J 2
(-3100 5425);
DISPLAY 0.702128 (-3100 5425);
PAINT GREEN (-3100 5425);
DISPLAY INVISIBLE (-3100 5425);
FORCEPROP 1 LAST HDL_TAP TRUE
J 2
(-3425 5350);
DISPLAY 0.702128 (-3425 5350);
PAINT GREEN (-3425 5350);
DISPLAY INVISIBLE (-3425 5350);
FORCEPROP 1 LAST PATH I249
J 2
(-3098 5475);
DISPLAY 0.872340 (-3098 5475);
PAINT GREEN (-3098 5475);
DISPLAY INVISIBLE (-3098 5475);
FORCEPROP 2 LAST ROOM RISER1
J 0
(-3600 5525);
DISPLAY 0.829787 (-3600 5525);
PAINT RED (-3600 5525);
DISPLAY INVISIBLE (-3600 5525);
FORCEADD TAP..6
R 2
(-3100 5575);
FORCEPROP 3 LASTPIN (-3150 5575) SIG_NAME GMI_CPU0_G0_CPU1_G2_TX_DP<1>
J 0
(-3140 5585);
DISPLAY 0.659574 (-3140 5585);
PAINT MONO (-3140 5585);
DISPLAY INVISIBLE (-3140 5585);
FORCEPROP 1 LASTPIN (-3150 5575) BN 1
J 2
(-3098 5583);
DISPLAY 0.489362 (-3098 5583);
PAINT MONO (-3098 5583);
FORCEPROP 2 LAST CDS_LIB mstr_standard
J 0
(-3100 5575);
DISPLAY INVISIBLE (-3100 5575);
FORCEPROP 2 LAST BOM_COST IO_SLOT
J 0
(-3600 5675);
DISPLAY 0.829787 (-3600 5675);
DISPLAY INVISIBLE (-3600 5675);
FORCEPROP 1 LAST BODY_TYPE PLUMBING
J 2
(-3100 5525);
DISPLAY 0.702128 (-3100 5525);
PAINT GREEN (-3100 5525);
DISPLAY INVISIBLE (-3100 5525);
FORCEPROP 1 LAST HDL_TAP TRUE
J 2
(-3425 5450);
DISPLAY 0.702128 (-3425 5450);
PAINT GREEN (-3425 5450);
DISPLAY INVISIBLE (-3425 5450);
FORCEPROP 1 LAST PATH I250
J 2
(-3098 5575);
DISPLAY 0.872340 (-3098 5575);
PAINT GREEN (-3098 5575);
DISPLAY INVISIBLE (-3098 5575);
FORCEPROP 2 LAST ROOM RISER1
J 0
(-3600 5625);
DISPLAY 0.829787 (-3600 5625);
PAINT RED (-3600 5625);
DISPLAY INVISIBLE (-3600 5625);
FORCEADD TAP..6
R 2
(-2950 5325);
FORCEPROP 3 LASTPIN (-3000 5325) SIG_NAME GMI_CPU0_G0_CPU1_G2_TX_DN<3>
J 0
(-2990 5335);
DISPLAY 0.659574 (-2990 5335);
PAINT MONO (-2990 5335);
DISPLAY INVISIBLE (-2990 5335);
FORCEPROP 1 LASTPIN (-3000 5325) BN 3
J 2
(-2948 5333);
DISPLAY 0.489362 (-2948 5333);
PAINT MONO (-2948 5333);
FORCEPROP 2 LAST CDS_LIB standard
J 0
(-2950 5325);
DISPLAY INVISIBLE (-2950 5325);
FORCEPROP 2 LAST BOM_COST IO_SLOT
J 0
(-3450 5425);
DISPLAY 0.829787 (-3450 5425);
DISPLAY INVISIBLE (-3450 5425);
FORCEPROP 1 LAST BODY_TYPE PLUMBING
J 2
(-2950 5275);
DISPLAY 0.702128 (-2950 5275);
PAINT GREEN (-2950 5275);
DISPLAY INVISIBLE (-2950 5275);
FORCEPROP 1 LAST HDL_TAP TRUE
J 2
(-3275 5200);
DISPLAY 0.702128 (-3275 5200);
PAINT GREEN (-3275 5200);
DISPLAY INVISIBLE (-3275 5200);
FORCEPROP 1 LAST PATH I251
J 2
(-2948 5325);
DISPLAY 0.872340 (-2948 5325);
PAINT GREEN (-2948 5325);
DISPLAY INVISIBLE (-2948 5325);
FORCEPROP 2 LAST ROOM RISER1
J 0
(-3450 5375);
DISPLAY 0.829787 (-3450 5375);
PAINT RED (-3450 5375);
DISPLAY INVISIBLE (-3450 5375);
FORCEADD TAP..6
R 2
(-2950 5225);
FORCEPROP 3 LASTPIN (-3000 5225) SIG_NAME GMI_CPU0_G0_CPU1_G2_TX_DN<4>
J 0
(-2990 5235);
DISPLAY 0.659574 (-2990 5235);
PAINT MONO (-2990 5235);
DISPLAY INVISIBLE (-2990 5235);
FORCEPROP 1 LASTPIN (-3000 5225) BN 4
J 2
(-2948 5233);
DISPLAY 0.489362 (-2948 5233);
PAINT MONO (-2948 5233);
FORCEPROP 2 LAST CDS_LIB standard
J 0
(-2950 5225);
DISPLAY INVISIBLE (-2950 5225);
FORCEPROP 2 LAST BOM_COST IO_SLOT
J 0
(-3450 5325);
DISPLAY 0.829787 (-3450 5325);
DISPLAY INVISIBLE (-3450 5325);
FORCEPROP 1 LAST BODY_TYPE PLUMBING
J 2
(-2950 5175);
DISPLAY 0.702128 (-2950 5175);
PAINT GREEN (-2950 5175);
DISPLAY INVISIBLE (-2950 5175);
FORCEPROP 1 LAST HDL_TAP TRUE
J 2
(-3275 5100);
DISPLAY 0.702128 (-3275 5100);
PAINT GREEN (-3275 5100);
DISPLAY INVISIBLE (-3275 5100);
FORCEPROP 1 LAST PATH I252
J 2
(-2948 5225);
DISPLAY 0.872340 (-2948 5225);
PAINT GREEN (-2948 5225);
DISPLAY INVISIBLE (-2948 5225);
FORCEPROP 2 LAST ROOM RISER1
J 0
(-3450 5275);
DISPLAY 0.829787 (-3450 5275);
PAINT RED (-3450 5275);
DISPLAY INVISIBLE (-3450 5275);
FORCEADD TAP..6
R 2
(-2950 5125);
FORCEPROP 3 LASTPIN (-3000 5125) SIG_NAME GMI_CPU0_G0_CPU1_G2_TX_DN<5>
J 0
(-2990 5135);
DISPLAY 0.659574 (-2990 5135);
PAINT MONO (-2990 5135);
DISPLAY INVISIBLE (-2990 5135);
FORCEPROP 1 LASTPIN (-3000 5125) BN 5
J 2
(-2948 5133);
DISPLAY 0.489362 (-2948 5133);
PAINT MONO (-2948 5133);
FORCEPROP 2 LAST CDS_LIB standard
J 0
(-2950 5125);
DISPLAY INVISIBLE (-2950 5125);
FORCEPROP 2 LAST BOM_COST IO_SLOT
J 0
(-3450 5225);
DISPLAY 0.829787 (-3450 5225);
DISPLAY INVISIBLE (-3450 5225);
FORCEPROP 1 LAST BODY_TYPE PLUMBING
J 2
(-2950 5075);
DISPLAY 0.702128 (-2950 5075);
PAINT GREEN (-2950 5075);
DISPLAY INVISIBLE (-2950 5075);
FORCEPROP 1 LAST HDL_TAP TRUE
J 2
(-3275 5000);
DISPLAY 0.702128 (-3275 5000);
PAINT GREEN (-3275 5000);
DISPLAY INVISIBLE (-3275 5000);
FORCEPROP 1 LAST PATH I253
J 2
(-2948 5125);
DISPLAY 0.872340 (-2948 5125);
PAINT GREEN (-2948 5125);
DISPLAY INVISIBLE (-2948 5125);
FORCEPROP 2 LAST ROOM RISER1
J 0
(-3450 5175);
DISPLAY 0.829787 (-3450 5175);
PAINT RED (-3450 5175);
DISPLAY INVISIBLE (-3450 5175);
FORCEADD TAP..6
R 2
(-3100 5275);
FORCEPROP 3 LASTPIN (-3150 5275) SIG_NAME GMI_CPU0_G0_CPU1_G2_TX_DP<4>
J 0
(-3140 5285);
DISPLAY 0.659574 (-3140 5285);
PAINT MONO (-3140 5285);
DISPLAY INVISIBLE (-3140 5285);
FORCEPROP 1 LASTPIN (-3150 5275) BN 4
J 2
(-3098 5283);
DISPLAY 0.489362 (-3098 5283);
PAINT MONO (-3098 5283);
FORCEPROP 2 LAST BOM_COST IO_SLOT
J 0
(-3600 5375);
DISPLAY 0.829787 (-3600 5375);
DISPLAY INVISIBLE (-3600 5375);
FORCEPROP 2 LAST CDS_LIB standard
J 0
(-3100 5275);
DISPLAY INVISIBLE (-3100 5275);
FORCEPROP 1 LAST BODY_TYPE PLUMBING
J 2
(-3100 5225);
DISPLAY 0.702128 (-3100 5225);
PAINT GREEN (-3100 5225);
DISPLAY INVISIBLE (-3100 5225);
FORCEPROP 1 LAST HDL_TAP TRUE
J 2
(-3425 5150);
DISPLAY 0.702128 (-3425 5150);
PAINT GREEN (-3425 5150);
DISPLAY INVISIBLE (-3425 5150);
FORCEPROP 1 LAST PATH I254
J 2
(-3098 5275);
DISPLAY 0.872340 (-3098 5275);
PAINT GREEN (-3098 5275);
DISPLAY INVISIBLE (-3098 5275);
FORCEPROP 2 LAST ROOM RISER1
J 0
(-3600 5325);
DISPLAY 0.829787 (-3600 5325);
PAINT RED (-3600 5325);
DISPLAY INVISIBLE (-3600 5325);
FORCEADD TAP..6
R 2
(-3100 5175);
FORCEPROP 3 LASTPIN (-3150 5175) SIG_NAME GMI_CPU0_G0_CPU1_G2_TX_DP<5>
J 0
(-3140 5185);
DISPLAY 0.659574 (-3140 5185);
PAINT MONO (-3140 5185);
DISPLAY INVISIBLE (-3140 5185);
FORCEPROP 1 LASTPIN (-3150 5175) BN 5
J 2
(-3098 5183);
DISPLAY 0.489362 (-3098 5183);
PAINT MONO (-3098 5183);
FORCEPROP 2 LAST BOM_COST IO_SLOT
J 0
(-3600 5275);
DISPLAY 0.829787 (-3600 5275);
DISPLAY INVISIBLE (-3600 5275);
FORCEPROP 2 LAST CDS_LIB standard
J 0
(-3100 5175);
DISPLAY INVISIBLE (-3100 5175);
FORCEPROP 1 LAST BODY_TYPE PLUMBING
J 2
(-3100 5125);
DISPLAY 0.702128 (-3100 5125);
PAINT GREEN (-3100 5125);
DISPLAY INVISIBLE (-3100 5125);
FORCEPROP 1 LAST HDL_TAP TRUE
J 2
(-3425 5050);
DISPLAY 0.702128 (-3425 5050);
PAINT GREEN (-3425 5050);
DISPLAY INVISIBLE (-3425 5050);
FORCEPROP 1 LAST PATH I255
J 2
(-3098 5175);
DISPLAY 0.872340 (-3098 5175);
PAINT GREEN (-3098 5175);
DISPLAY INVISIBLE (-3098 5175);
FORCEPROP 2 LAST ROOM RISER1
J 0
(-3600 5225);
DISPLAY 0.829787 (-3600 5225);
PAINT RED (-3600 5225);
DISPLAY INVISIBLE (-3600 5225);
FORCEADD TAP..6
R 2
(-3100 5375);
FORCEPROP 3 LASTPIN (-3150 5375) SIG_NAME GMI_CPU0_G0_CPU1_G2_TX_DP<3>
J 0
(-3140 5385);
DISPLAY 0.659574 (-3140 5385);
PAINT MONO (-3140 5385);
DISPLAY INVISIBLE (-3140 5385);
FORCEPROP 1 LASTPIN (-3150 5375) BN 3
J 2
(-3098 5383);
DISPLAY 0.489362 (-3098 5383);
PAINT MONO (-3098 5383);
FORCEPROP 2 LAST BOM_COST IO_SLOT
J 0
(-3600 5475);
DISPLAY 0.829787 (-3600 5475);
DISPLAY INVISIBLE (-3600 5475);
FORCEPROP 2 LAST CDS_LIB standard
J 0
(-3100 5375);
DISPLAY INVISIBLE (-3100 5375);
FORCEPROP 1 LAST BODY_TYPE PLUMBING
J 2
(-3100 5325);
DISPLAY 0.702128 (-3100 5325);
PAINT GREEN (-3100 5325);
DISPLAY INVISIBLE (-3100 5325);
FORCEPROP 1 LAST HDL_TAP TRUE
J 2
(-3425 5250);
DISPLAY 0.702128 (-3425 5250);
PAINT GREEN (-3425 5250);
DISPLAY INVISIBLE (-3425 5250);
FORCEPROP 1 LAST PATH I256
J 2
(-3098 5375);
DISPLAY 0.872340 (-3098 5375);
PAINT GREEN (-3098 5375);
DISPLAY INVISIBLE (-3098 5375);
FORCEPROP 2 LAST ROOM RISER1
J 0
(-3600 5425);
DISPLAY 0.829787 (-3600 5425);
PAINT RED (-3600 5425);
DISPLAY INVISIBLE (-3600 5425);
FORCEADD TAP..6
R 2
(-2950 5025);
FORCEPROP 3 LASTPIN (-3000 5025) SIG_NAME GMI_CPU0_G0_CPU1_G2_TX_DN<6>
J 0
(-2990 5035);
DISPLAY 0.659574 (-2990 5035);
PAINT MONO (-2990 5035);
DISPLAY INVISIBLE (-2990 5035);
FORCEPROP 1 LASTPIN (-3000 5025) BN 6
J 2
(-2948 5033);
DISPLAY 0.489362 (-2948 5033);
PAINT MONO (-2948 5033);
FORCEPROP 2 LAST CDS_LIB standard
J 0
(-2950 5025);
DISPLAY INVISIBLE (-2950 5025);
FORCEPROP 2 LAST BOM_COST IO_SLOT
J 0
(-3450 5125);
DISPLAY 0.829787 (-3450 5125);
DISPLAY INVISIBLE (-3450 5125);
FORCEPROP 1 LAST BODY_TYPE PLUMBING
J 2
(-2950 4975);
DISPLAY 0.702128 (-2950 4975);
PAINT GREEN (-2950 4975);
DISPLAY INVISIBLE (-2950 4975);
FORCEPROP 1 LAST HDL_TAP TRUE
J 2
(-3275 4900);
DISPLAY 0.702128 (-3275 4900);
PAINT GREEN (-3275 4900);
DISPLAY INVISIBLE (-3275 4900);
FORCEPROP 1 LAST PATH I257
J 2
(-2948 5025);
DISPLAY 0.872340 (-2948 5025);
PAINT GREEN (-2948 5025);
DISPLAY INVISIBLE (-2948 5025);
FORCEPROP 2 LAST ROOM RISER1
J 0
(-3450 5075);
DISPLAY 0.829787 (-3450 5075);
PAINT RED (-3450 5075);
DISPLAY INVISIBLE (-3450 5075);
FORCEADD TAP..6
R 2
(-2950 4925);
FORCEPROP 3 LASTPIN (-3000 4925) SIG_NAME GMI_CPU0_G0_CPU1_G2_TX_DN<7>
J 0
(-2990 4935);
DISPLAY 0.659574 (-2990 4935);
PAINT MONO (-2990 4935);
DISPLAY INVISIBLE (-2990 4935);
FORCEPROP 1 LASTPIN (-3000 4925) BN 7
J 2
(-2948 4933);
DISPLAY 0.489362 (-2948 4933);
PAINT MONO (-2948 4933);
FORCEPROP 2 LAST CDS_LIB standard
J 0
(-2950 4925);
DISPLAY INVISIBLE (-2950 4925);
FORCEPROP 2 LAST BOM_COST IO_SLOT
J 0
(-3450 5025);
DISPLAY 0.829787 (-3450 5025);
DISPLAY INVISIBLE (-3450 5025);
FORCEPROP 1 LAST BODY_TYPE PLUMBING
J 2
(-2950 4875);
DISPLAY 0.702128 (-2950 4875);
PAINT GREEN (-2950 4875);
DISPLAY INVISIBLE (-2950 4875);
FORCEPROP 1 LAST HDL_TAP TRUE
J 2
(-3275 4800);
DISPLAY 0.702128 (-3275 4800);
PAINT GREEN (-3275 4800);
DISPLAY INVISIBLE (-3275 4800);
FORCEPROP 1 LAST PATH I258
J 2
(-2948 4925);
DISPLAY 0.872340 (-2948 4925);
PAINT GREEN (-2948 4925);
DISPLAY INVISIBLE (-2948 4925);
FORCEPROP 2 LAST ROOM RISER1
J 0
(-3450 4975);
DISPLAY 0.829787 (-3450 4975);
PAINT RED (-3450 4975);
DISPLAY INVISIBLE (-3450 4975);
FORCEADD TAP..6
R 2
(-3100 4875);
FORCEPROP 3 LASTPIN (-3150 4875) SIG_NAME GMI_CPU0_G0_CPU1_G2_TX_DP<8>
J 0
(-3140 4885);
DISPLAY 0.659574 (-3140 4885);
PAINT MONO (-3140 4885);
DISPLAY INVISIBLE (-3140 4885);
FORCEPROP 1 LASTPIN (-3150 4875) BN 8
J 2
(-3098 4883);
DISPLAY 0.489362 (-3098 4883);
PAINT MONO (-3098 4883);
FORCEPROP 2 LAST BOM_COST IO_SLOT
J 0
(-3600 4975);
DISPLAY 0.829787 (-3600 4975);
DISPLAY INVISIBLE (-3600 4975);
FORCEPROP 2 LAST CDS_LIB standard
J 0
(-3100 4875);
DISPLAY INVISIBLE (-3100 4875);
FORCEPROP 1 LAST BODY_TYPE PLUMBING
J 2
(-3100 4825);
DISPLAY 0.702128 (-3100 4825);
PAINT GREEN (-3100 4825);
DISPLAY INVISIBLE (-3100 4825);
FORCEPROP 1 LAST HDL_TAP TRUE
J 2
(-3425 4750);
DISPLAY 0.702128 (-3425 4750);
PAINT GREEN (-3425 4750);
DISPLAY INVISIBLE (-3425 4750);
FORCEPROP 1 LAST PATH I259
J 2
(-3098 4875);
DISPLAY 0.872340 (-3098 4875);
PAINT GREEN (-3098 4875);
DISPLAY INVISIBLE (-3098 4875);
FORCEPROP 2 LAST ROOM RISER1
J 0
(-3600 4925);
DISPLAY 0.829787 (-3600 4925);
PAINT RED (-3600 4925);
DISPLAY INVISIBLE (-3600 4925);
FORCEADD TAP..6
R 2
(-3100 4975);
FORCEPROP 3 LASTPIN (-3150 4975) SIG_NAME GMI_CPU0_G0_CPU1_G2_TX_DP<7>
J 0
(-3140 4985);
DISPLAY 0.659574 (-3140 4985);
PAINT MONO (-3140 4985);
DISPLAY INVISIBLE (-3140 4985);
FORCEPROP 1 LASTPIN (-3150 4975) BN 7
J 2
(-3098 4983);
DISPLAY 0.489362 (-3098 4983);
PAINT MONO (-3098 4983);
FORCEPROP 2 LAST BOM_COST IO_SLOT
J 0
(-3600 5075);
DISPLAY 0.829787 (-3600 5075);
DISPLAY INVISIBLE (-3600 5075);
FORCEPROP 2 LAST CDS_LIB standard
J 0
(-3100 4975);
DISPLAY INVISIBLE (-3100 4975);
FORCEPROP 1 LAST BODY_TYPE PLUMBING
J 2
(-3100 4925);
DISPLAY 0.702128 (-3100 4925);
PAINT GREEN (-3100 4925);
DISPLAY INVISIBLE (-3100 4925);
FORCEPROP 1 LAST HDL_TAP TRUE
J 2
(-3425 4850);
DISPLAY 0.702128 (-3425 4850);
PAINT GREEN (-3425 4850);
DISPLAY INVISIBLE (-3425 4850);
FORCEPROP 1 LAST PATH I260
J 2
(-3098 4975);
DISPLAY 0.872340 (-3098 4975);
PAINT GREEN (-3098 4975);
DISPLAY INVISIBLE (-3098 4975);
FORCEPROP 2 LAST ROOM RISER1
J 0
(-3600 5025);
DISPLAY 0.829787 (-3600 5025);
PAINT RED (-3600 5025);
DISPLAY INVISIBLE (-3600 5025);
FORCEADD TAP..6
R 2
(-3100 5075);
FORCEPROP 3 LASTPIN (-3150 5075) SIG_NAME GMI_CPU0_G0_CPU1_G2_TX_DP<6>
J 0
(-3140 5085);
DISPLAY 0.659574 (-3140 5085);
PAINT MONO (-3140 5085);
DISPLAY INVISIBLE (-3140 5085);
FORCEPROP 1 LASTPIN (-3150 5075) BN 6
J 2
(-3098 5083);
DISPLAY 0.489362 (-3098 5083);
PAINT MONO (-3098 5083);
FORCEPROP 2 LAST BOM_COST IO_SLOT
J 0
(-3600 5175);
DISPLAY 0.829787 (-3600 5175);
DISPLAY INVISIBLE (-3600 5175);
FORCEPROP 2 LAST CDS_LIB standard
J 0
(-3100 5075);
DISPLAY INVISIBLE (-3100 5075);
FORCEPROP 1 LAST BODY_TYPE PLUMBING
J 2
(-3100 5025);
DISPLAY 0.702128 (-3100 5025);
PAINT GREEN (-3100 5025);
DISPLAY INVISIBLE (-3100 5025);
FORCEPROP 1 LAST HDL_TAP TRUE
J 2
(-3425 4950);
DISPLAY 0.702128 (-3425 4950);
PAINT GREEN (-3425 4950);
DISPLAY INVISIBLE (-3425 4950);
FORCEPROP 1 LAST PATH I261
J 2
(-3098 5075);
DISPLAY 0.872340 (-3098 5075);
PAINT GREEN (-3098 5075);
DISPLAY INVISIBLE (-3098 5075);
FORCEPROP 2 LAST ROOM RISER1
J 0
(-3600 5125);
DISPLAY 0.829787 (-3600 5125);
PAINT RED (-3600 5125);
DISPLAY INVISIBLE (-3600 5125);
FORCEADD TAP..6
R 2
(-2950 4825);
FORCEPROP 3 LASTPIN (-3000 4825) SIG_NAME GMI_CPU0_G0_CPU1_G2_TX_DN<8>
J 0
(-2990 4835);
DISPLAY 0.659574 (-2990 4835);
PAINT MONO (-2990 4835);
DISPLAY INVISIBLE (-2990 4835);
FORCEPROP 1 LASTPIN (-3000 4825) BN 8
J 2
(-2948 4833);
DISPLAY 0.489362 (-2948 4833);
PAINT MONO (-2948 4833);
FORCEPROP 2 LAST CDS_LIB standard
J 0
(-2950 4825);
DISPLAY INVISIBLE (-2950 4825);
FORCEPROP 2 LAST BOM_COST IO_SLOT
J 0
(-3450 4925);
DISPLAY 0.829787 (-3450 4925);
DISPLAY INVISIBLE (-3450 4925);
FORCEPROP 1 LAST BODY_TYPE PLUMBING
J 2
(-2950 4775);
DISPLAY 0.702128 (-2950 4775);
PAINT GREEN (-2950 4775);
DISPLAY INVISIBLE (-2950 4775);
FORCEPROP 1 LAST HDL_TAP TRUE
J 2
(-3275 4700);
DISPLAY 0.702128 (-3275 4700);
PAINT GREEN (-3275 4700);
DISPLAY INVISIBLE (-3275 4700);
FORCEPROP 1 LAST PATH I262
J 2
(-2948 4825);
DISPLAY 0.872340 (-2948 4825);
PAINT GREEN (-2948 4825);
DISPLAY INVISIBLE (-2948 4825);
FORCEPROP 2 LAST ROOM RISER1
J 0
(-3450 4875);
DISPLAY 0.829787 (-3450 4875);
PAINT RED (-3450 4875);
DISPLAY INVISIBLE (-3450 4875);
FORCEADD TAP..6
R 2
(-2950 4725);
FORCEPROP 3 LASTPIN (-3000 4725) SIG_NAME GMI_CPU0_G0_CPU1_G2_TX_DN<9>
J 0
(-2990 4735);
DISPLAY 0.659574 (-2990 4735);
PAINT MONO (-2990 4735);
DISPLAY INVISIBLE (-2990 4735);
FORCEPROP 1 LASTPIN (-3000 4725) BN 9
J 2
(-2948 4733);
DISPLAY 0.489362 (-2948 4733);
PAINT MONO (-2948 4733);
FORCEPROP 2 LAST CDS_LIB standard
J 0
(-2950 4725);
DISPLAY INVISIBLE (-2950 4725);
FORCEPROP 2 LAST BOM_COST IO_SLOT
J 0
(-3450 4825);
DISPLAY 0.829787 (-3450 4825);
DISPLAY INVISIBLE (-3450 4825);
FORCEPROP 1 LAST BODY_TYPE PLUMBING
J 2
(-2950 4675);
DISPLAY 0.702128 (-2950 4675);
PAINT GREEN (-2950 4675);
DISPLAY INVISIBLE (-2950 4675);
FORCEPROP 1 LAST HDL_TAP TRUE
J 2
(-3275 4600);
DISPLAY 0.702128 (-3275 4600);
PAINT GREEN (-3275 4600);
DISPLAY INVISIBLE (-3275 4600);
FORCEPROP 1 LAST PATH I263
J 2
(-2948 4725);
DISPLAY 0.872340 (-2948 4725);
PAINT GREEN (-2948 4725);
DISPLAY INVISIBLE (-2948 4725);
FORCEPROP 2 LAST ROOM RISER1
J 0
(-3450 4775);
DISPLAY 0.829787 (-3450 4775);
PAINT RED (-3450 4775);
DISPLAY INVISIBLE (-3450 4775);
FORCEADD TAP..6
R 2
(-2950 4625);
FORCEPROP 3 LASTPIN (-3000 4625) SIG_NAME GMI_CPU0_G0_CPU1_G2_TX_DN<10>
J 0
(-2990 4635);
DISPLAY 0.659574 (-2990 4635);
PAINT MONO (-2990 4635);
DISPLAY INVISIBLE (-2990 4635);
FORCEPROP 1 LASTPIN (-3000 4625) BN 10
J 2
(-2948 4633);
DISPLAY 0.489362 (-2948 4633);
PAINT MONO (-2948 4633);
FORCEPROP 2 LAST CDS_LIB standard
J 0
(-2950 4625);
DISPLAY INVISIBLE (-2950 4625);
FORCEPROP 2 LAST BOM_COST IO_SLOT
J 0
(-3450 4725);
DISPLAY 0.829787 (-3450 4725);
DISPLAY INVISIBLE (-3450 4725);
FORCEPROP 1 LAST BODY_TYPE PLUMBING
J 2
(-2950 4575);
DISPLAY 0.702128 (-2950 4575);
PAINT GREEN (-2950 4575);
DISPLAY INVISIBLE (-2950 4575);
FORCEPROP 1 LAST HDL_TAP TRUE
J 2
(-3275 4500);
DISPLAY 0.702128 (-3275 4500);
PAINT GREEN (-3275 4500);
DISPLAY INVISIBLE (-3275 4500);
FORCEPROP 1 LAST PATH I264
J 2
(-2948 4625);
DISPLAY 0.872340 (-2948 4625);
PAINT GREEN (-2948 4625);
DISPLAY INVISIBLE (-2948 4625);
FORCEPROP 2 LAST ROOM RISER1
J 0
(-3450 4675);
DISPLAY 0.829787 (-3450 4675);
PAINT RED (-3450 4675);
DISPLAY INVISIBLE (-3450 4675);
FORCEADD TAP..6
R 2
(-3100 4675);
FORCEPROP 3 LASTPIN (-3150 4675) SIG_NAME GMI_CPU0_G0_CPU1_G2_TX_DP<10>
J 0
(-3140 4685);
DISPLAY 0.659574 (-3140 4685);
PAINT MONO (-3140 4685);
DISPLAY INVISIBLE (-3140 4685);
FORCEPROP 1 LASTPIN (-3150 4675) BN 10
J 2
(-3098 4683);
DISPLAY 0.489362 (-3098 4683);
PAINT MONO (-3098 4683);
FORCEPROP 2 LAST BOM_COST IO_SLOT
J 0
(-3600 4775);
DISPLAY 0.829787 (-3600 4775);
DISPLAY INVISIBLE (-3600 4775);
FORCEPROP 2 LAST CDS_LIB standard
J 0
(-3100 4675);
DISPLAY INVISIBLE (-3100 4675);
FORCEPROP 1 LAST BODY_TYPE PLUMBING
J 2
(-3100 4625);
DISPLAY 0.702128 (-3100 4625);
PAINT GREEN (-3100 4625);
DISPLAY INVISIBLE (-3100 4625);
FORCEPROP 1 LAST HDL_TAP TRUE
J 2
(-3425 4550);
DISPLAY 0.702128 (-3425 4550);
PAINT GREEN (-3425 4550);
DISPLAY INVISIBLE (-3425 4550);
FORCEPROP 1 LAST PATH I265
J 2
(-3098 4675);
DISPLAY 0.872340 (-3098 4675);
PAINT GREEN (-3098 4675);
DISPLAY INVISIBLE (-3098 4675);
FORCEPROP 2 LAST ROOM RISER1
J 0
(-3600 4725);
DISPLAY 0.829787 (-3600 4725);
PAINT RED (-3600 4725);
DISPLAY INVISIBLE (-3600 4725);
FORCEADD TAP..6
R 2
(-3100 4775);
FORCEPROP 3 LASTPIN (-3150 4775) SIG_NAME GMI_CPU0_G0_CPU1_G2_TX_DP<9>
J 0
(-3140 4785);
DISPLAY 0.659574 (-3140 4785);
PAINT MONO (-3140 4785);
DISPLAY INVISIBLE (-3140 4785);
FORCEPROP 1 LASTPIN (-3150 4775) BN 9
J 2
(-3098 4783);
DISPLAY 0.489362 (-3098 4783);
PAINT MONO (-3098 4783);
FORCEPROP 2 LAST BOM_COST IO_SLOT
J 0
(-3600 4875);
DISPLAY 0.829787 (-3600 4875);
DISPLAY INVISIBLE (-3600 4875);
FORCEPROP 2 LAST CDS_LIB standard
J 0
(-3100 4775);
DISPLAY INVISIBLE (-3100 4775);
FORCEPROP 1 LAST BODY_TYPE PLUMBING
J 2
(-3100 4725);
DISPLAY 0.702128 (-3100 4725);
PAINT GREEN (-3100 4725);
DISPLAY INVISIBLE (-3100 4725);
FORCEPROP 1 LAST HDL_TAP TRUE
J 2
(-3425 4650);
DISPLAY 0.702128 (-3425 4650);
PAINT GREEN (-3425 4650);
DISPLAY INVISIBLE (-3425 4650);
FORCEPROP 1 LAST PATH I266
J 2
(-3098 4775);
DISPLAY 0.872340 (-3098 4775);
PAINT GREEN (-3098 4775);
DISPLAY INVISIBLE (-3098 4775);
FORCEPROP 2 LAST ROOM RISER1
J 0
(-3600 4825);
DISPLAY 0.829787 (-3600 4825);
PAINT RED (-3600 4825);
DISPLAY INVISIBLE (-3600 4825);
FORCEADD TAP..6
R 2
(-2950 4525);
FORCEPROP 3 LASTPIN (-3000 4525) SIG_NAME GMI_CPU0_G0_CPU1_G2_TX_DN<11>
J 0
(-2990 4535);
DISPLAY 0.659574 (-2990 4535);
PAINT MONO (-2990 4535);
DISPLAY INVISIBLE (-2990 4535);
FORCEPROP 1 LASTPIN (-3000 4525) BN 11
J 2
(-2948 4533);
DISPLAY 0.489362 (-2948 4533);
PAINT MONO (-2948 4533);
FORCEPROP 2 LAST CDS_LIB standard
J 0
(-2950 4525);
DISPLAY INVISIBLE (-2950 4525);
FORCEPROP 2 LAST BOM_COST IO_SLOT
J 0
(-3450 4625);
DISPLAY 0.829787 (-3450 4625);
DISPLAY INVISIBLE (-3450 4625);
FORCEPROP 1 LAST BODY_TYPE PLUMBING
J 2
(-2950 4475);
DISPLAY 0.702128 (-2950 4475);
PAINT GREEN (-2950 4475);
DISPLAY INVISIBLE (-2950 4475);
FORCEPROP 1 LAST HDL_TAP TRUE
J 2
(-3275 4400);
DISPLAY 0.702128 (-3275 4400);
PAINT GREEN (-3275 4400);
DISPLAY INVISIBLE (-3275 4400);
FORCEPROP 1 LAST PATH I267
J 2
(-2948 4525);
DISPLAY 0.872340 (-2948 4525);
PAINT GREEN (-2948 4525);
DISPLAY INVISIBLE (-2948 4525);
FORCEPROP 2 LAST ROOM RISER1
J 0
(-3450 4575);
DISPLAY 0.829787 (-3450 4575);
PAINT RED (-3450 4575);
DISPLAY INVISIBLE (-3450 4575);
FORCEADD TAP..6
R 2
(-2950 4425);
FORCEPROP 3 LASTPIN (-3000 4425) SIG_NAME GMI_CPU0_G0_CPU1_G2_TX_DN<12>
J 0
(-2990 4435);
DISPLAY 0.659574 (-2990 4435);
PAINT MONO (-2990 4435);
DISPLAY INVISIBLE (-2990 4435);
FORCEPROP 1 LASTPIN (-3000 4425) BN 12
J 2
(-2948 4433);
DISPLAY 0.489362 (-2948 4433);
PAINT MONO (-2948 4433);
FORCEPROP 2 LAST CDS_LIB standard
J 0
(-2950 4425);
DISPLAY INVISIBLE (-2950 4425);
FORCEPROP 2 LAST BOM_COST IO_SLOT
J 0
(-3450 4525);
DISPLAY 0.829787 (-3450 4525);
DISPLAY INVISIBLE (-3450 4525);
FORCEPROP 1 LAST BODY_TYPE PLUMBING
J 2
(-2950 4375);
DISPLAY 0.702128 (-2950 4375);
PAINT GREEN (-2950 4375);
DISPLAY INVISIBLE (-2950 4375);
FORCEPROP 1 LAST HDL_TAP TRUE
J 2
(-3275 4300);
DISPLAY 0.702128 (-3275 4300);
PAINT GREEN (-3275 4300);
DISPLAY INVISIBLE (-3275 4300);
FORCEPROP 1 LAST PATH I268
J 2
(-2948 4425);
DISPLAY 0.872340 (-2948 4425);
PAINT GREEN (-2948 4425);
DISPLAY INVISIBLE (-2948 4425);
FORCEPROP 2 LAST ROOM RISER1
J 0
(-3450 4475);
DISPLAY 0.829787 (-3450 4475);
PAINT RED (-3450 4475);
DISPLAY INVISIBLE (-3450 4475);
FORCEADD TAP..6
R 2
(-3100 4375);
FORCEPROP 3 LASTPIN (-3150 4375) SIG_NAME GMI_CPU0_G0_CPU1_G2_TX_DP<13>
J 0
(-3140 4385);
DISPLAY 0.659574 (-3140 4385);
PAINT MONO (-3140 4385);
DISPLAY INVISIBLE (-3140 4385);
FORCEPROP 1 LASTPIN (-3150 4375) BN 13
J 2
(-3098 4383);
DISPLAY 0.489362 (-3098 4383);
PAINT MONO (-3098 4383);
FORCEPROP 2 LAST BOM_COST IO_SLOT
J 0
(-3600 4475);
DISPLAY 0.829787 (-3600 4475);
DISPLAY INVISIBLE (-3600 4475);
FORCEPROP 2 LAST CDS_LIB standard
J 0
(-3100 4375);
DISPLAY INVISIBLE (-3100 4375);
FORCEPROP 1 LAST BODY_TYPE PLUMBING
J 2
(-3100 4325);
DISPLAY 0.702128 (-3100 4325);
PAINT GREEN (-3100 4325);
DISPLAY INVISIBLE (-3100 4325);
FORCEPROP 1 LAST HDL_TAP TRUE
J 2
(-3425 4250);
DISPLAY 0.702128 (-3425 4250);
PAINT GREEN (-3425 4250);
DISPLAY INVISIBLE (-3425 4250);
FORCEPROP 1 LAST PATH I269
J 2
(-3098 4375);
DISPLAY 0.872340 (-3098 4375);
PAINT GREEN (-3098 4375);
DISPLAY INVISIBLE (-3098 4375);
FORCEPROP 2 LAST ROOM RISER1
J 0
(-3600 4425);
DISPLAY 0.829787 (-3600 4425);
PAINT RED (-3600 4425);
DISPLAY INVISIBLE (-3600 4425);
FORCEADD TAP..6
R 2
(-3100 4475);
FORCEPROP 3 LASTPIN (-3150 4475) SIG_NAME GMI_CPU0_G0_CPU1_G2_TX_DP<12>
J 0
(-3140 4485);
DISPLAY 0.659574 (-3140 4485);
PAINT MONO (-3140 4485);
DISPLAY INVISIBLE (-3140 4485);
FORCEPROP 1 LASTPIN (-3150 4475) BN 12
J 2
(-3098 4483);
DISPLAY 0.489362 (-3098 4483);
PAINT MONO (-3098 4483);
FORCEPROP 2 LAST BOM_COST IO_SLOT
J 0
(-3600 4575);
DISPLAY 0.829787 (-3600 4575);
DISPLAY INVISIBLE (-3600 4575);
FORCEPROP 2 LAST CDS_LIB standard
J 0
(-3100 4475);
DISPLAY INVISIBLE (-3100 4475);
FORCEPROP 1 LAST BODY_TYPE PLUMBING
J 2
(-3100 4425);
DISPLAY 0.702128 (-3100 4425);
PAINT GREEN (-3100 4425);
DISPLAY INVISIBLE (-3100 4425);
FORCEPROP 1 LAST HDL_TAP TRUE
J 2
(-3425 4350);
DISPLAY 0.702128 (-3425 4350);
PAINT GREEN (-3425 4350);
DISPLAY INVISIBLE (-3425 4350);
FORCEPROP 1 LAST PATH I270
J 2
(-3098 4475);
DISPLAY 0.872340 (-3098 4475);
PAINT GREEN (-3098 4475);
DISPLAY INVISIBLE (-3098 4475);
FORCEPROP 2 LAST ROOM RISER1
J 0
(-3600 4525);
DISPLAY 0.829787 (-3600 4525);
PAINT RED (-3600 4525);
DISPLAY INVISIBLE (-3600 4525);
FORCEADD TAP..6
R 2
(-3100 4575);
FORCEPROP 3 LASTPIN (-3150 4575) SIG_NAME GMI_CPU0_G0_CPU1_G2_TX_DP<11>
J 0
(-3140 4585);
DISPLAY 0.659574 (-3140 4585);
PAINT MONO (-3140 4585);
DISPLAY INVISIBLE (-3140 4585);
FORCEPROP 1 LASTPIN (-3150 4575) BN 11
J 2
(-3098 4583);
DISPLAY 0.489362 (-3098 4583);
PAINT MONO (-3098 4583);
FORCEPROP 2 LAST BOM_COST IO_SLOT
J 0
(-3600 4675);
DISPLAY 0.829787 (-3600 4675);
DISPLAY INVISIBLE (-3600 4675);
FORCEPROP 2 LAST CDS_LIB standard
J 0
(-3100 4575);
DISPLAY INVISIBLE (-3100 4575);
FORCEPROP 1 LAST BODY_TYPE PLUMBING
J 2
(-3100 4525);
DISPLAY 0.702128 (-3100 4525);
PAINT GREEN (-3100 4525);
DISPLAY INVISIBLE (-3100 4525);
FORCEPROP 1 LAST HDL_TAP TRUE
J 2
(-3425 4450);
DISPLAY 0.702128 (-3425 4450);
PAINT GREEN (-3425 4450);
DISPLAY INVISIBLE (-3425 4450);
FORCEPROP 1 LAST PATH I271
J 2
(-3098 4575);
DISPLAY 0.872340 (-3098 4575);
PAINT GREEN (-3098 4575);
DISPLAY INVISIBLE (-3098 4575);
FORCEPROP 2 LAST ROOM RISER1
J 0
(-3600 4625);
DISPLAY 0.829787 (-3600 4625);
PAINT RED (-3600 4625);
DISPLAY INVISIBLE (-3600 4625);
FORCEADD TAP..6
R 2
(-2950 4225);
FORCEPROP 3 LASTPIN (-3000 4225) SIG_NAME GMI_CPU0_G0_CPU1_G2_TX_DN<14>
J 0
(-2990 4235);
DISPLAY 0.659574 (-2990 4235);
PAINT MONO (-2990 4235);
DISPLAY INVISIBLE (-2990 4235);
FORCEPROP 1 LASTPIN (-3000 4225) BN 14
J 2
(-2948 4233);
DISPLAY 0.489362 (-2948 4233);
PAINT MONO (-2948 4233);
FORCEPROP 2 LAST BOM_COST IO_SLOT
J 0
(-3450 4325);
DISPLAY 0.829787 (-3450 4325);
DISPLAY INVISIBLE (-3450 4325);
FORCEPROP 2 LAST CDS_LIB standard
J 0
(-2950 4225);
DISPLAY INVISIBLE (-2950 4225);
FORCEPROP 1 LAST BODY_TYPE PLUMBING
J 2
(-2950 4175);
DISPLAY 0.702128 (-2950 4175);
PAINT GREEN (-2950 4175);
DISPLAY INVISIBLE (-2950 4175);
FORCEPROP 1 LAST HDL_TAP TRUE
J 2
(-3275 4100);
DISPLAY 0.702128 (-3275 4100);
PAINT GREEN (-3275 4100);
DISPLAY INVISIBLE (-3275 4100);
FORCEPROP 1 LAST PATH I272
J 2
(-2948 4225);
DISPLAY 0.872340 (-2948 4225);
PAINT GREEN (-2948 4225);
DISPLAY INVISIBLE (-2948 4225);
FORCEPROP 2 LAST ROOM RISER1
J 0
(-3450 4275);
DISPLAY 0.829787 (-3450 4275);
PAINT RED (-3450 4275);
DISPLAY INVISIBLE (-3450 4275);
FORCEADD TAP..6
R 2
(-2950 4125);
FORCEPROP 3 LASTPIN (-3000 4125) SIG_NAME GMI_CPU0_G0_CPU1_G2_TX_DN<15>
J 0
(-2990 4135);
DISPLAY 0.659574 (-2990 4135);
PAINT MONO (-2990 4135);
DISPLAY INVISIBLE (-2990 4135);
FORCEPROP 1 LASTPIN (-3000 4125) BN 15
J 2
(-2948 4133);
DISPLAY 0.489362 (-2948 4133);
PAINT MONO (-2948 4133);
FORCEPROP 2 LAST CDS_LIB standard
J 0
(-2950 4125);
DISPLAY INVISIBLE (-2950 4125);
FORCEPROP 2 LAST BOM_COST IO_SLOT
J 0
(-3450 4225);
DISPLAY 0.829787 (-3450 4225);
DISPLAY INVISIBLE (-3450 4225);
FORCEPROP 1 LAST BODY_TYPE PLUMBING
J 2
(-2950 4075);
DISPLAY 0.702128 (-2950 4075);
PAINT GREEN (-2950 4075);
DISPLAY INVISIBLE (-2950 4075);
FORCEPROP 1 LAST HDL_TAP TRUE
J 2
(-3275 4000);
DISPLAY 0.702128 (-3275 4000);
PAINT GREEN (-3275 4000);
DISPLAY INVISIBLE (-3275 4000);
FORCEPROP 1 LAST PATH I273
J 2
(-2948 4125);
DISPLAY 0.872340 (-2948 4125);
PAINT GREEN (-2948 4125);
DISPLAY INVISIBLE (-2948 4125);
FORCEPROP 2 LAST ROOM RISER1
J 0
(-3450 4175);
DISPLAY 0.829787 (-3450 4175);
PAINT RED (-3450 4175);
DISPLAY INVISIBLE (-3450 4175);
FORCEADD TAP..6
R 2
(-2950 4325);
FORCEPROP 3 LASTPIN (-3000 4325) SIG_NAME GMI_CPU0_G0_CPU1_G2_TX_DN<13>
J 0
(-2990 4335);
DISPLAY 0.659574 (-2990 4335);
PAINT MONO (-2990 4335);
DISPLAY INVISIBLE (-2990 4335);
FORCEPROP 1 LASTPIN (-3000 4325) BN 13
J 2
(-2948 4333);
DISPLAY 0.489362 (-2948 4333);
PAINT MONO (-2948 4333);
FORCEPROP 2 LAST CDS_LIB standard
J 0
(-2950 4325);
DISPLAY INVISIBLE (-2950 4325);
FORCEPROP 2 LAST BOM_COST IO_SLOT
J 0
(-3450 4425);
DISPLAY 0.829787 (-3450 4425);
DISPLAY INVISIBLE (-3450 4425);
FORCEPROP 1 LAST BODY_TYPE PLUMBING
J 2
(-2950 4275);
DISPLAY 0.702128 (-2950 4275);
PAINT GREEN (-2950 4275);
DISPLAY INVISIBLE (-2950 4275);
FORCEPROP 1 LAST HDL_TAP TRUE
J 2
(-3275 4200);
DISPLAY 0.702128 (-3275 4200);
PAINT GREEN (-3275 4200);
DISPLAY INVISIBLE (-3275 4200);
FORCEPROP 1 LAST PATH I274
J 2
(-2948 4325);
DISPLAY 0.872340 (-2948 4325);
PAINT GREEN (-2948 4325);
DISPLAY INVISIBLE (-2948 4325);
FORCEPROP 2 LAST ROOM RISER1
J 0
(-3450 4375);
DISPLAY 0.829787 (-3450 4375);
PAINT RED (-3450 4375);
DISPLAY INVISIBLE (-3450 4375);
FORCEADD TAP..6
R 2
(-3100 4175);
FORCEPROP 3 LASTPIN (-3150 4175) SIG_NAME GMI_CPU0_G0_CPU1_G2_TX_DP<15>
J 0
(-3140 4185);
DISPLAY 0.659574 (-3140 4185);
PAINT MONO (-3140 4185);
DISPLAY INVISIBLE (-3140 4185);
FORCEPROP 1 LASTPIN (-3150 4175) BN 15
J 2
(-3098 4183);
DISPLAY 0.489362 (-3098 4183);
PAINT MONO (-3098 4183);
FORCEPROP 2 LAST BOM_COST IO_SLOT
J 0
(-3600 4275);
DISPLAY 0.829787 (-3600 4275);
DISPLAY INVISIBLE (-3600 4275);
FORCEPROP 2 LAST CDS_LIB standard
J 0
(-3100 4175);
DISPLAY INVISIBLE (-3100 4175);
FORCEPROP 1 LAST BODY_TYPE PLUMBING
J 2
(-3100 4125);
DISPLAY 0.702128 (-3100 4125);
PAINT GREEN (-3100 4125);
DISPLAY INVISIBLE (-3100 4125);
FORCEPROP 1 LAST HDL_TAP TRUE
J 2
(-3425 4050);
DISPLAY 0.702128 (-3425 4050);
PAINT GREEN (-3425 4050);
DISPLAY INVISIBLE (-3425 4050);
FORCEPROP 1 LAST PATH I275
J 2
(-3098 4175);
DISPLAY 0.872340 (-3098 4175);
PAINT GREEN (-3098 4175);
DISPLAY INVISIBLE (-3098 4175);
FORCEPROP 2 LAST ROOM RISER1
J 0
(-3600 4225);
DISPLAY 0.829787 (-3600 4225);
PAINT RED (-3600 4225);
DISPLAY INVISIBLE (-3600 4225);
FORCEADD TAP..6
R 2
(-3100 4275);
FORCEPROP 3 LASTPIN (-3150 4275) SIG_NAME GMI_CPU0_G0_CPU1_G2_TX_DP<14>
J 0
(-3140 4285);
DISPLAY 0.659574 (-3140 4285);
PAINT MONO (-3140 4285);
DISPLAY INVISIBLE (-3140 4285);
FORCEPROP 1 LASTPIN (-3150 4275) BN 14
J 2
(-3098 4283);
DISPLAY 0.489362 (-3098 4283);
PAINT MONO (-3098 4283);
FORCEPROP 2 LAST BOM_COST IO_SLOT
J 0
(-3600 4375);
DISPLAY 0.829787 (-3600 4375);
DISPLAY INVISIBLE (-3600 4375);
FORCEPROP 2 LAST CDS_LIB standard
J 0
(-3100 4275);
DISPLAY INVISIBLE (-3100 4275);
FORCEPROP 1 LAST BODY_TYPE PLUMBING
J 2
(-3100 4225);
DISPLAY 0.702128 (-3100 4225);
PAINT GREEN (-3100 4225);
DISPLAY INVISIBLE (-3100 4225);
FORCEPROP 1 LAST HDL_TAP TRUE
J 2
(-3425 4150);
DISPLAY 0.702128 (-3425 4150);
PAINT GREEN (-3425 4150);
DISPLAY INVISIBLE (-3425 4150);
FORCEPROP 1 LAST PATH I276
J 2
(-3098 4275);
DISPLAY 0.872340 (-3098 4275);
PAINT GREEN (-3098 4275);
DISPLAY INVISIBLE (-3098 4275);
FORCEPROP 2 LAST ROOM RISER1
J 0
(-3600 4325);
DISPLAY 0.829787 (-3600 4325);
PAINT RED (-3600 4325);
DISPLAY INVISIBLE (-3600 4325);
FORCEADD TAP..6
(-6525 5675);
FORCEPROP 3 LASTPIN (-6475 5675) SIG_NAME GMI_CPU1_G2_CPU0_G0_TX_DP<0>
J 0
(-6465 5685);
DISPLAY 0.659574 (-6465 5685);
PAINT MONO (-6465 5685);
DISPLAY INVISIBLE (-6465 5685);
FORCEPROP 1 LASTPIN (-6475 5675) BN 0
J 0
(-6527 5683);
DISPLAY 0.489362 (-6527 5683);
PAINT MONO (-6527 5683);
FORCEPROP 2 LAST CDS_LIB mstr_standard
J 0
(-6525 5675);
DISPLAY INVISIBLE (-6525 5675);
FORCEPROP 1 LAST BODY_TYPE PLUMBING
J 0
(-6525 5625);
DISPLAY 0.574468 (-6525 5625);
PAINT GREEN (-6525 5625);
DISPLAY INVISIBLE (-6525 5625);
FORCEPROP 1 LAST HDL_TAP TRUE
J 0
(-6200 5550);
DISPLAY 0.574468 (-6200 5550);
PAINT GREEN (-6200 5550);
DISPLAY INVISIBLE (-6200 5550);
FORCEPROP 1 LAST PATH I277
J 0
(-6527 5675);
DISPLAY 0.872340 (-6527 5675);
PAINT GREEN (-6527 5675);
DISPLAY INVISIBLE (-6527 5675);
FORCEADD TAP..6
(-6525 5575);
FORCEPROP 3 LASTPIN (-6475 5575) SIG_NAME GMI_CPU1_G2_CPU0_G0_TX_DP<1>
J 0
(-6465 5585);
DISPLAY 0.659574 (-6465 5585);
PAINT MONO (-6465 5585);
DISPLAY INVISIBLE (-6465 5585);
FORCEPROP 1 LASTPIN (-6475 5575) BN 1
J 0
(-6527 5583);
DISPLAY 0.489362 (-6527 5583);
PAINT MONO (-6527 5583);
FORCEPROP 2 LAST CDS_LIB mstr_standard
J 0
(-6525 5575);
DISPLAY INVISIBLE (-6525 5575);
FORCEPROP 1 LAST BODY_TYPE PLUMBING
J 0
(-6525 5525);
DISPLAY 0.574468 (-6525 5525);
PAINT GREEN (-6525 5525);
DISPLAY INVISIBLE (-6525 5525);
FORCEPROP 1 LAST HDL_TAP TRUE
J 0
(-6200 5450);
DISPLAY 0.574468 (-6200 5450);
PAINT GREEN (-6200 5450);
DISPLAY INVISIBLE (-6200 5450);
FORCEPROP 1 LAST PATH I278
J 0
(-6527 5575);
DISPLAY 0.872340 (-6527 5575);
PAINT GREEN (-6527 5575);
DISPLAY INVISIBLE (-6527 5575);
FORCEADD TAP..6
(-6525 5475);
FORCEPROP 3 LASTPIN (-6475 5475) SIG_NAME GMI_CPU1_G2_CPU0_G0_TX_DP<2>
J 0
(-6465 5485);
DISPLAY 0.659574 (-6465 5485);
PAINT MONO (-6465 5485);
DISPLAY INVISIBLE (-6465 5485);
FORCEPROP 1 LASTPIN (-6475 5475) BN 2
J 0
(-6527 5483);
DISPLAY 0.489362 (-6527 5483);
PAINT MONO (-6527 5483);
FORCEPROP 2 LAST CDS_LIB mstr_standard
J 0
(-6525 5475);
DISPLAY INVISIBLE (-6525 5475);
FORCEPROP 1 LAST BODY_TYPE PLUMBING
J 0
(-6525 5425);
DISPLAY 0.574468 (-6525 5425);
PAINT GREEN (-6525 5425);
DISPLAY INVISIBLE (-6525 5425);
FORCEPROP 1 LAST HDL_TAP TRUE
J 0
(-6200 5350);
DISPLAY 0.574468 (-6200 5350);
PAINT GREEN (-6200 5350);
DISPLAY INVISIBLE (-6200 5350);
FORCEPROP 1 LAST PATH I279
J 0
(-6527 5475);
DISPLAY 0.872340 (-6527 5475);
PAINT GREEN (-6527 5475);
DISPLAY INVISIBLE (-6527 5475);
FORCEADD TAP..6
(-6675 5625);
FORCEPROP 3 LASTPIN (-6625 5625) SIG_NAME GMI_CPU1_G2_CPU0_G0_TX_DN<0>
J 0
(-6615 5635);
DISPLAY 0.659574 (-6615 5635);
PAINT MONO (-6615 5635);
DISPLAY INVISIBLE (-6615 5635);
FORCEPROP 1 LASTPIN (-6625 5625) BN 0
J 0
(-6677 5633);
DISPLAY 0.489362 (-6677 5633);
PAINT MONO (-6677 5633);
FORCEPROP 2 LAST CDS_LIB mstr_standard
J 0
(-6675 5625);
DISPLAY INVISIBLE (-6675 5625);
FORCEPROP 1 LAST BODY_TYPE PLUMBING
J 0
(-6675 5575);
DISPLAY 0.574468 (-6675 5575);
PAINT GREEN (-6675 5575);
DISPLAY INVISIBLE (-6675 5575);
FORCEPROP 1 LAST HDL_TAP TRUE
J 0
(-6350 5500);
DISPLAY 0.574468 (-6350 5500);
PAINT GREEN (-6350 5500);
DISPLAY INVISIBLE (-6350 5500);
FORCEPROP 1 LAST PATH I280
J 0
(-6677 5625);
DISPLAY 0.872340 (-6677 5625);
PAINT GREEN (-6677 5625);
DISPLAY INVISIBLE (-6677 5625);
FORCEADD TAP..6
(-6675 5525);
FORCEPROP 3 LASTPIN (-6625 5525) SIG_NAME GMI_CPU1_G2_CPU0_G0_TX_DN<1>
J 0
(-6615 5535);
DISPLAY 0.659574 (-6615 5535);
PAINT MONO (-6615 5535);
DISPLAY INVISIBLE (-6615 5535);
FORCEPROP 1 LASTPIN (-6625 5525) BN 1
J 0
(-6677 5533);
DISPLAY 0.489362 (-6677 5533);
PAINT MONO (-6677 5533);
FORCEPROP 2 LAST CDS_LIB mstr_standard
J 0
(-6675 5525);
DISPLAY INVISIBLE (-6675 5525);
FORCEPROP 1 LAST BODY_TYPE PLUMBING
J 0
(-6675 5475);
DISPLAY 0.574468 (-6675 5475);
PAINT GREEN (-6675 5475);
DISPLAY INVISIBLE (-6675 5475);
FORCEPROP 1 LAST HDL_TAP TRUE
J 0
(-6350 5400);
DISPLAY 0.574468 (-6350 5400);
PAINT GREEN (-6350 5400);
DISPLAY INVISIBLE (-6350 5400);
FORCEPROP 1 LAST PATH I281
J 0
(-6677 5525);
DISPLAY 0.872340 (-6677 5525);
PAINT GREEN (-6677 5525);
DISPLAY INVISIBLE (-6677 5525);
FORCEADD TAP..6
(-6675 5425);
FORCEPROP 3 LASTPIN (-6625 5425) SIG_NAME GMI_CPU1_G2_CPU0_G0_TX_DN<2>
J 0
(-6615 5435);
DISPLAY 0.659574 (-6615 5435);
PAINT MONO (-6615 5435);
DISPLAY INVISIBLE (-6615 5435);
FORCEPROP 1 LASTPIN (-6625 5425) BN 2
J 0
(-6677 5433);
DISPLAY 0.489362 (-6677 5433);
PAINT MONO (-6677 5433);
FORCEPROP 2 LAST CDS_LIB standard
J 0
(-6675 5425);
DISPLAY INVISIBLE (-6675 5425);
FORCEPROP 1 LAST BODY_TYPE PLUMBING
J 0
(-6675 5375);
DISPLAY 0.574468 (-6675 5375);
PAINT GREEN (-6675 5375);
DISPLAY INVISIBLE (-6675 5375);
FORCEPROP 1 LAST HDL_TAP TRUE
J 0
(-6350 5300);
DISPLAY 0.574468 (-6350 5300);
PAINT GREEN (-6350 5300);
DISPLAY INVISIBLE (-6350 5300);
FORCEPROP 1 LAST PATH I282
J 0
(-6677 5425);
DISPLAY 0.872340 (-6677 5425);
PAINT GREEN (-6677 5425);
DISPLAY INVISIBLE (-6677 5425);
FORCEADD TAP..6
(-6525 5275);
FORCEPROP 3 LASTPIN (-6475 5275) SIG_NAME GMI_CPU1_G2_CPU0_G0_TX_DP<4>
J 0
(-6465 5285);
DISPLAY 0.659574 (-6465 5285);
PAINT MONO (-6465 5285);
DISPLAY INVISIBLE (-6465 5285);
FORCEPROP 1 LASTPIN (-6475 5275) BN 4
J 0
(-6527 5283);
DISPLAY 0.489362 (-6527 5283);
PAINT MONO (-6527 5283);
FORCEPROP 2 LAST CDS_LIB standard
J 0
(-6525 5275);
DISPLAY INVISIBLE (-6525 5275);
FORCEPROP 1 LAST BODY_TYPE PLUMBING
J 0
(-6525 5225);
DISPLAY 0.574468 (-6525 5225);
PAINT GREEN (-6525 5225);
DISPLAY INVISIBLE (-6525 5225);
FORCEPROP 1 LAST HDL_TAP TRUE
J 0
(-6200 5150);
DISPLAY 0.574468 (-6200 5150);
PAINT GREEN (-6200 5150);
DISPLAY INVISIBLE (-6200 5150);
FORCEPROP 1 LAST PATH I283
J 0
(-6527 5275);
DISPLAY 0.872340 (-6527 5275);
PAINT GREEN (-6527 5275);
DISPLAY INVISIBLE (-6527 5275);
FORCEADD TAP..6
(-6525 5375);
FORCEPROP 3 LASTPIN (-6475 5375) SIG_NAME GMI_CPU1_G2_CPU0_G0_TX_DP<3>
J 0
(-6465 5385);
DISPLAY 0.659574 (-6465 5385);
PAINT MONO (-6465 5385);
DISPLAY INVISIBLE (-6465 5385);
FORCEPROP 1 LASTPIN (-6475 5375) BN 3
J 0
(-6527 5383);
DISPLAY 0.489362 (-6527 5383);
PAINT MONO (-6527 5383);
FORCEPROP 2 LAST CDS_LIB standard
J 0
(-6525 5375);
DISPLAY INVISIBLE (-6525 5375);
FORCEPROP 1 LAST BODY_TYPE PLUMBING
J 0
(-6525 5325);
DISPLAY 0.574468 (-6525 5325);
PAINT GREEN (-6525 5325);
DISPLAY INVISIBLE (-6525 5325);
FORCEPROP 1 LAST HDL_TAP TRUE
J 0
(-6200 5250);
DISPLAY 0.574468 (-6200 5250);
PAINT GREEN (-6200 5250);
DISPLAY INVISIBLE (-6200 5250);
FORCEPROP 1 LAST PATH I284
J 0
(-6527 5375);
DISPLAY 0.872340 (-6527 5375);
PAINT GREEN (-6527 5375);
DISPLAY INVISIBLE (-6527 5375);
FORCEADD TAP..6
(-6525 5175);
FORCEPROP 3 LASTPIN (-6475 5175) SIG_NAME GMI_CPU1_G2_CPU0_G0_TX_DP<5>
J 0
(-6465 5185);
DISPLAY 0.659574 (-6465 5185);
PAINT MONO (-6465 5185);
DISPLAY INVISIBLE (-6465 5185);
FORCEPROP 1 LASTPIN (-6475 5175) BN 5
J 0
(-6527 5183);
DISPLAY 0.489362 (-6527 5183);
PAINT MONO (-6527 5183);
FORCEPROP 2 LAST CDS_LIB standard
J 0
(-6525 5175);
DISPLAY INVISIBLE (-6525 5175);
FORCEPROP 1 LAST BODY_TYPE PLUMBING
J 0
(-6525 5125);
DISPLAY 0.574468 (-6525 5125);
PAINT GREEN (-6525 5125);
DISPLAY INVISIBLE (-6525 5125);
FORCEPROP 1 LAST HDL_TAP TRUE
J 0
(-6200 5050);
DISPLAY 0.574468 (-6200 5050);
PAINT GREEN (-6200 5050);
DISPLAY INVISIBLE (-6200 5050);
FORCEPROP 1 LAST PATH I285
J 0
(-6527 5175);
DISPLAY 0.872340 (-6527 5175);
PAINT GREEN (-6527 5175);
DISPLAY INVISIBLE (-6527 5175);
FORCEADD TAP..6
(-6675 5325);
FORCEPROP 3 LASTPIN (-6625 5325) SIG_NAME GMI_CPU1_G2_CPU0_G0_TX_DN<3>
J 0
(-6615 5335);
DISPLAY 0.659574 (-6615 5335);
PAINT MONO (-6615 5335);
DISPLAY INVISIBLE (-6615 5335);
FORCEPROP 1 LASTPIN (-6625 5325) BN 3
J 0
(-6677 5333);
DISPLAY 0.489362 (-6677 5333);
PAINT MONO (-6677 5333);
FORCEPROP 2 LAST CDS_LIB standard
J 0
(-6675 5325);
DISPLAY INVISIBLE (-6675 5325);
FORCEPROP 1 LAST BODY_TYPE PLUMBING
J 0
(-6675 5275);
DISPLAY 0.574468 (-6675 5275);
PAINT GREEN (-6675 5275);
DISPLAY INVISIBLE (-6675 5275);
FORCEPROP 1 LAST HDL_TAP TRUE
J 0
(-6350 5200);
DISPLAY 0.574468 (-6350 5200);
PAINT GREEN (-6350 5200);
DISPLAY INVISIBLE (-6350 5200);
FORCEPROP 1 LAST PATH I286
J 0
(-6677 5325);
DISPLAY 0.872340 (-6677 5325);
PAINT GREEN (-6677 5325);
DISPLAY INVISIBLE (-6677 5325);
FORCEADD TAP..6
(-6675 5225);
FORCEPROP 3 LASTPIN (-6625 5225) SIG_NAME GMI_CPU1_G2_CPU0_G0_TX_DN<4>
J 0
(-6615 5235);
DISPLAY 0.659574 (-6615 5235);
PAINT MONO (-6615 5235);
DISPLAY INVISIBLE (-6615 5235);
FORCEPROP 1 LASTPIN (-6625 5225) BN 4
J 0
(-6677 5233);
DISPLAY 0.489362 (-6677 5233);
PAINT MONO (-6677 5233);
FORCEPROP 2 LAST CDS_LIB standard
J 0
(-6675 5225);
DISPLAY INVISIBLE (-6675 5225);
FORCEPROP 1 LAST BODY_TYPE PLUMBING
J 0
(-6675 5175);
DISPLAY 0.574468 (-6675 5175);
PAINT GREEN (-6675 5175);
DISPLAY INVISIBLE (-6675 5175);
FORCEPROP 1 LAST HDL_TAP TRUE
J 0
(-6350 5100);
DISPLAY 0.574468 (-6350 5100);
PAINT GREEN (-6350 5100);
DISPLAY INVISIBLE (-6350 5100);
FORCEPROP 1 LAST PATH I287
J 0
(-6677 5225);
DISPLAY 0.872340 (-6677 5225);
PAINT GREEN (-6677 5225);
DISPLAY INVISIBLE (-6677 5225);
FORCEADD TAP..6
(-6675 5125);
FORCEPROP 3 LASTPIN (-6625 5125) SIG_NAME GMI_CPU1_G2_CPU0_G0_TX_DN<5>
J 0
(-6615 5135);
DISPLAY 0.659574 (-6615 5135);
PAINT MONO (-6615 5135);
DISPLAY INVISIBLE (-6615 5135);
FORCEPROP 1 LASTPIN (-6625 5125) BN 5
J 0
(-6677 5133);
DISPLAY 0.489362 (-6677 5133);
PAINT MONO (-6677 5133);
FORCEPROP 2 LAST CDS_LIB standard
J 0
(-6675 5125);
DISPLAY INVISIBLE (-6675 5125);
FORCEPROP 1 LAST BODY_TYPE PLUMBING
J 0
(-6675 5075);
DISPLAY 0.574468 (-6675 5075);
PAINT GREEN (-6675 5075);
DISPLAY INVISIBLE (-6675 5075);
FORCEPROP 1 LAST HDL_TAP TRUE
J 0
(-6350 5000);
DISPLAY 0.574468 (-6350 5000);
PAINT GREEN (-6350 5000);
DISPLAY INVISIBLE (-6350 5000);
FORCEPROP 1 LAST PATH I288
J 0
(-6677 5125);
DISPLAY 0.872340 (-6677 5125);
PAINT GREEN (-6677 5125);
DISPLAY INVISIBLE (-6677 5125);
FORCEADD TAP..6
(-6525 5075);
FORCEPROP 3 LASTPIN (-6475 5075) SIG_NAME GMI_CPU1_G2_CPU0_G0_TX_DP<6>
J 0
(-6465 5085);
DISPLAY 0.659574 (-6465 5085);
PAINT MONO (-6465 5085);
DISPLAY INVISIBLE (-6465 5085);
FORCEPROP 1 LASTPIN (-6475 5075) BN 6
J 0
(-6527 5083);
DISPLAY 0.489362 (-6527 5083);
PAINT MONO (-6527 5083);
FORCEPROP 2 LAST CDS_LIB standard
J 0
(-6525 5075);
DISPLAY INVISIBLE (-6525 5075);
FORCEPROP 1 LAST BODY_TYPE PLUMBING
J 0
(-6525 5025);
DISPLAY 0.574468 (-6525 5025);
PAINT GREEN (-6525 5025);
DISPLAY INVISIBLE (-6525 5025);
FORCEPROP 1 LAST HDL_TAP TRUE
J 0
(-6200 4950);
DISPLAY 0.574468 (-6200 4950);
PAINT GREEN (-6200 4950);
DISPLAY INVISIBLE (-6200 4950);
FORCEPROP 1 LAST PATH I289
J 0
(-6527 5075);
DISPLAY 0.872340 (-6527 5075);
PAINT GREEN (-6527 5075);
DISPLAY INVISIBLE (-6527 5075);
FORCEADD TAP..6
(-6525 4975);
FORCEPROP 3 LASTPIN (-6475 4975) SIG_NAME GMI_CPU1_G2_CPU0_G0_TX_DP<7>
J 0
(-6465 4985);
DISPLAY 0.659574 (-6465 4985);
PAINT MONO (-6465 4985);
DISPLAY INVISIBLE (-6465 4985);
FORCEPROP 1 LASTPIN (-6475 4975) BN 7
J 0
(-6527 4983);
DISPLAY 0.489362 (-6527 4983);
PAINT MONO (-6527 4983);
FORCEPROP 2 LAST CDS_LIB standard
J 0
(-6525 4975);
DISPLAY INVISIBLE (-6525 4975);
FORCEPROP 1 LAST BODY_TYPE PLUMBING
J 0
(-6525 4925);
DISPLAY 0.574468 (-6525 4925);
PAINT GREEN (-6525 4925);
DISPLAY INVISIBLE (-6525 4925);
FORCEPROP 1 LAST HDL_TAP TRUE
J 0
(-6200 4850);
DISPLAY 0.574468 (-6200 4850);
PAINT GREEN (-6200 4850);
DISPLAY INVISIBLE (-6200 4850);
FORCEPROP 1 LAST PATH I290
J 0
(-6527 4975);
DISPLAY 0.872340 (-6527 4975);
PAINT GREEN (-6527 4975);
DISPLAY INVISIBLE (-6527 4975);
FORCEADD TAP..6
(-6525 4875);
FORCEPROP 3 LASTPIN (-6475 4875) SIG_NAME GMI_CPU1_G2_CPU0_G0_TX_DP<8>
J 0
(-6465 4885);
DISPLAY 0.659574 (-6465 4885);
PAINT MONO (-6465 4885);
DISPLAY INVISIBLE (-6465 4885);
FORCEPROP 1 LASTPIN (-6475 4875) BN 8
J 0
(-6527 4883);
DISPLAY 0.489362 (-6527 4883);
PAINT MONO (-6527 4883);
FORCEPROP 2 LAST CDS_LIB standard
J 0
(-6525 4875);
DISPLAY INVISIBLE (-6525 4875);
FORCEPROP 1 LAST BODY_TYPE PLUMBING
J 0
(-6525 4825);
DISPLAY 0.574468 (-6525 4825);
PAINT GREEN (-6525 4825);
DISPLAY INVISIBLE (-6525 4825);
FORCEPROP 1 LAST HDL_TAP TRUE
J 0
(-6200 4750);
DISPLAY 0.574468 (-6200 4750);
PAINT GREEN (-6200 4750);
DISPLAY INVISIBLE (-6200 4750);
FORCEPROP 1 LAST PATH I291
J 0
(-6527 4875);
DISPLAY 0.872340 (-6527 4875);
PAINT GREEN (-6527 4875);
DISPLAY INVISIBLE (-6527 4875);
FORCEADD TAP..6
(-6675 5025);
FORCEPROP 3 LASTPIN (-6625 5025) SIG_NAME GMI_CPU1_G2_CPU0_G0_TX_DN<6>
J 0
(-6615 5035);
DISPLAY 0.659574 (-6615 5035);
PAINT MONO (-6615 5035);
DISPLAY INVISIBLE (-6615 5035);
FORCEPROP 1 LASTPIN (-6625 5025) BN 6
J 0
(-6677 5033);
DISPLAY 0.489362 (-6677 5033);
PAINT MONO (-6677 5033);
FORCEPROP 2 LAST CDS_LIB standard
J 0
(-6675 5025);
DISPLAY INVISIBLE (-6675 5025);
FORCEPROP 1 LAST BODY_TYPE PLUMBING
J 0
(-6675 4975);
DISPLAY 0.574468 (-6675 4975);
PAINT GREEN (-6675 4975);
DISPLAY INVISIBLE (-6675 4975);
FORCEPROP 1 LAST HDL_TAP TRUE
J 0
(-6350 4900);
DISPLAY 0.574468 (-6350 4900);
PAINT GREEN (-6350 4900);
DISPLAY INVISIBLE (-6350 4900);
FORCEPROP 1 LAST PATH I292
J 0
(-6677 5025);
DISPLAY 0.872340 (-6677 5025);
PAINT GREEN (-6677 5025);
DISPLAY INVISIBLE (-6677 5025);
FORCEADD TAP..6
(-6675 4925);
FORCEPROP 3 LASTPIN (-6625 4925) SIG_NAME GMI_CPU1_G2_CPU0_G0_TX_DN<7>
J 0
(-6615 4935);
DISPLAY 0.659574 (-6615 4935);
PAINT MONO (-6615 4935);
DISPLAY INVISIBLE (-6615 4935);
FORCEPROP 1 LASTPIN (-6625 4925) BN 7
J 0
(-6677 4933);
DISPLAY 0.489362 (-6677 4933);
PAINT MONO (-6677 4933);
FORCEPROP 2 LAST CDS_LIB standard
J 0
(-6675 4925);
DISPLAY INVISIBLE (-6675 4925);
FORCEPROP 1 LAST BODY_TYPE PLUMBING
J 0
(-6675 4875);
DISPLAY 0.574468 (-6675 4875);
PAINT GREEN (-6675 4875);
DISPLAY INVISIBLE (-6675 4875);
FORCEPROP 1 LAST HDL_TAP TRUE
J 0
(-6350 4800);
DISPLAY 0.574468 (-6350 4800);
PAINT GREEN (-6350 4800);
DISPLAY INVISIBLE (-6350 4800);
FORCEPROP 1 LAST PATH I293
J 0
(-6677 4925);
DISPLAY 0.872340 (-6677 4925);
PAINT GREEN (-6677 4925);
DISPLAY INVISIBLE (-6677 4925);
FORCEADD TAP..6
(-6525 4775);
FORCEPROP 3 LASTPIN (-6475 4775) SIG_NAME GMI_CPU1_G2_CPU0_G0_TX_DP<9>
J 0
(-6465 4785);
DISPLAY 0.659574 (-6465 4785);
PAINT MONO (-6465 4785);
DISPLAY INVISIBLE (-6465 4785);
FORCEPROP 1 LASTPIN (-6475 4775) BN 9
J 0
(-6527 4783);
DISPLAY 0.489362 (-6527 4783);
PAINT MONO (-6527 4783);
FORCEPROP 2 LAST CDS_LIB standard
J 0
(-6525 4775);
DISPLAY INVISIBLE (-6525 4775);
FORCEPROP 1 LAST BODY_TYPE PLUMBING
J 0
(-6525 4725);
DISPLAY 0.574468 (-6525 4725);
PAINT GREEN (-6525 4725);
DISPLAY INVISIBLE (-6525 4725);
FORCEPROP 1 LAST HDL_TAP TRUE
J 0
(-6200 4650);
DISPLAY 0.574468 (-6200 4650);
PAINT GREEN (-6200 4650);
DISPLAY INVISIBLE (-6200 4650);
FORCEPROP 1 LAST PATH I294
J 0
(-6527 4775);
DISPLAY 0.872340 (-6527 4775);
PAINT GREEN (-6527 4775);
DISPLAY INVISIBLE (-6527 4775);
FORCEADD TAP..6
(-6525 4675);
FORCEPROP 3 LASTPIN (-6475 4675) SIG_NAME GMI_CPU1_G2_CPU0_G0_TX_DP<10>
J 0
(-6465 4685);
DISPLAY 0.659574 (-6465 4685);
PAINT MONO (-6465 4685);
DISPLAY INVISIBLE (-6465 4685);
FORCEPROP 1 LASTPIN (-6475 4675) BN 10
J 0
(-6527 4683);
DISPLAY 0.489362 (-6527 4683);
PAINT MONO (-6527 4683);
FORCEPROP 2 LAST CDS_LIB standard
J 0
(-6525 4675);
DISPLAY INVISIBLE (-6525 4675);
FORCEPROP 1 LAST BODY_TYPE PLUMBING
J 0
(-6525 4625);
DISPLAY 0.574468 (-6525 4625);
PAINT GREEN (-6525 4625);
DISPLAY INVISIBLE (-6525 4625);
FORCEPROP 1 LAST HDL_TAP TRUE
J 0
(-6200 4550);
DISPLAY 0.574468 (-6200 4550);
PAINT GREEN (-6200 4550);
DISPLAY INVISIBLE (-6200 4550);
FORCEPROP 1 LAST PATH I295
J 0
(-6527 4675);
DISPLAY 0.872340 (-6527 4675);
PAINT GREEN (-6527 4675);
DISPLAY INVISIBLE (-6527 4675);
FORCEADD TAP..6
(-6675 4825);
FORCEPROP 3 LASTPIN (-6625 4825) SIG_NAME GMI_CPU1_G2_CPU0_G0_TX_DN<8>
J 0
(-6615 4835);
DISPLAY 0.659574 (-6615 4835);
PAINT MONO (-6615 4835);
DISPLAY INVISIBLE (-6615 4835);
FORCEPROP 1 LASTPIN (-6625 4825) BN 8
J 0
(-6677 4833);
DISPLAY 0.489362 (-6677 4833);
PAINT MONO (-6677 4833);
FORCEPROP 2 LAST CDS_LIB standard
J 0
(-6675 4825);
DISPLAY INVISIBLE (-6675 4825);
FORCEPROP 1 LAST BODY_TYPE PLUMBING
J 0
(-6675 4775);
DISPLAY 0.574468 (-6675 4775);
PAINT GREEN (-6675 4775);
DISPLAY INVISIBLE (-6675 4775);
FORCEPROP 1 LAST HDL_TAP TRUE
J 0
(-6350 4700);
DISPLAY 0.574468 (-6350 4700);
PAINT GREEN (-6350 4700);
DISPLAY INVISIBLE (-6350 4700);
FORCEPROP 1 LAST PATH I296
J 0
(-6677 4825);
DISPLAY 0.872340 (-6677 4825);
PAINT GREEN (-6677 4825);
DISPLAY INVISIBLE (-6677 4825);
FORCEADD TAP..6
(-6675 4725);
FORCEPROP 3 LASTPIN (-6625 4725) SIG_NAME GMI_CPU1_G2_CPU0_G0_TX_DN<9>
J 0
(-6615 4735);
DISPLAY 0.659574 (-6615 4735);
PAINT MONO (-6615 4735);
DISPLAY INVISIBLE (-6615 4735);
FORCEPROP 1 LASTPIN (-6625 4725) BN 9
J 0
(-6677 4733);
DISPLAY 0.489362 (-6677 4733);
PAINT MONO (-6677 4733);
FORCEPROP 2 LAST CDS_LIB standard
J 0
(-6675 4725);
DISPLAY INVISIBLE (-6675 4725);
FORCEPROP 1 LAST BODY_TYPE PLUMBING
J 0
(-6675 4675);
DISPLAY 0.574468 (-6675 4675);
PAINT GREEN (-6675 4675);
DISPLAY INVISIBLE (-6675 4675);
FORCEPROP 1 LAST HDL_TAP TRUE
J 0
(-6350 4600);
DISPLAY 0.574468 (-6350 4600);
PAINT GREEN (-6350 4600);
DISPLAY INVISIBLE (-6350 4600);
FORCEPROP 1 LAST PATH I297
J 0
(-6677 4725);
DISPLAY 0.872340 (-6677 4725);
PAINT GREEN (-6677 4725);
DISPLAY INVISIBLE (-6677 4725);
FORCEADD TAP..6
(-6675 4625);
FORCEPROP 3 LASTPIN (-6625 4625) SIG_NAME GMI_CPU1_G2_CPU0_G0_TX_DN<10>
J 0
(-6615 4635);
DISPLAY 0.659574 (-6615 4635);
PAINT MONO (-6615 4635);
DISPLAY INVISIBLE (-6615 4635);
FORCEPROP 1 LASTPIN (-6625 4625) BN 10
J 0
(-6677 4633);
DISPLAY 0.489362 (-6677 4633);
PAINT MONO (-6677 4633);
FORCEPROP 2 LAST CDS_LIB standard
J 0
(-6675 4625);
DISPLAY INVISIBLE (-6675 4625);
FORCEPROP 1 LAST BODY_TYPE PLUMBING
J 0
(-6675 4575);
DISPLAY 0.574468 (-6675 4575);
PAINT GREEN (-6675 4575);
DISPLAY INVISIBLE (-6675 4575);
FORCEPROP 1 LAST HDL_TAP TRUE
J 0
(-6350 4500);
DISPLAY 0.574468 (-6350 4500);
PAINT GREEN (-6350 4500);
DISPLAY INVISIBLE (-6350 4500);
FORCEPROP 1 LAST PATH I298
J 0
(-6677 4625);
DISPLAY 0.872340 (-6677 4625);
PAINT GREEN (-6677 4625);
DISPLAY INVISIBLE (-6677 4625);
FORCEADD TAP..6
(-6525 4575);
FORCEPROP 3 LASTPIN (-6475 4575) SIG_NAME GMI_CPU1_G2_CPU0_G0_TX_DP<11>
J 0
(-6465 4585);
DISPLAY 0.659574 (-6465 4585);
PAINT MONO (-6465 4585);
DISPLAY INVISIBLE (-6465 4585);
FORCEPROP 1 LASTPIN (-6475 4575) BN 11
J 0
(-6527 4583);
DISPLAY 0.489362 (-6527 4583);
PAINT MONO (-6527 4583);
FORCEPROP 2 LAST CDS_LIB standard
J 0
(-6525 4575);
DISPLAY INVISIBLE (-6525 4575);
FORCEPROP 1 LAST BODY_TYPE PLUMBING
J 0
(-6525 4525);
DISPLAY 0.574468 (-6525 4525);
PAINT GREEN (-6525 4525);
DISPLAY INVISIBLE (-6525 4525);
FORCEPROP 1 LAST HDL_TAP TRUE
J 0
(-6200 4450);
DISPLAY 0.574468 (-6200 4450);
PAINT GREEN (-6200 4450);
DISPLAY INVISIBLE (-6200 4450);
FORCEPROP 1 LAST PATH I299
J 0
(-6527 4575);
DISPLAY 0.872340 (-6527 4575);
PAINT GREEN (-6527 4575);
DISPLAY INVISIBLE (-6527 4575);
FORCEADD TAP..6
(-6525 4475);
FORCEPROP 3 LASTPIN (-6475 4475) SIG_NAME GMI_CPU1_G2_CPU0_G0_TX_DP<12>
J 0
(-6465 4485);
DISPLAY 0.659574 (-6465 4485);
PAINT MONO (-6465 4485);
DISPLAY INVISIBLE (-6465 4485);
FORCEPROP 1 LASTPIN (-6475 4475) BN 12
J 0
(-6527 4483);
DISPLAY 0.489362 (-6527 4483);
PAINT MONO (-6527 4483);
FORCEPROP 2 LAST CDS_LIB standard
J 0
(-6525 4475);
DISPLAY INVISIBLE (-6525 4475);
FORCEPROP 1 LAST BODY_TYPE PLUMBING
J 0
(-6525 4425);
DISPLAY 0.574468 (-6525 4425);
PAINT GREEN (-6525 4425);
DISPLAY INVISIBLE (-6525 4425);
FORCEPROP 1 LAST HDL_TAP TRUE
J 0
(-6200 4350);
DISPLAY 0.574468 (-6200 4350);
PAINT GREEN (-6200 4350);
DISPLAY INVISIBLE (-6200 4350);
FORCEPROP 1 LAST PATH I300
J 0
(-6527 4475);
DISPLAY 0.872340 (-6527 4475);
PAINT GREEN (-6527 4475);
DISPLAY INVISIBLE (-6527 4475);
FORCEADD TAP..6
(-6525 4375);
FORCEPROP 3 LASTPIN (-6475 4375) SIG_NAME GMI_CPU1_G2_CPU0_G0_TX_DP<13>
J 0
(-6465 4385);
DISPLAY 0.659574 (-6465 4385);
PAINT MONO (-6465 4385);
DISPLAY INVISIBLE (-6465 4385);
FORCEPROP 1 LASTPIN (-6475 4375) BN 13
J 0
(-6527 4383);
DISPLAY 0.489362 (-6527 4383);
PAINT MONO (-6527 4383);
FORCEPROP 2 LAST CDS_LIB standard
J 0
(-6525 4375);
DISPLAY INVISIBLE (-6525 4375);
FORCEPROP 1 LAST BODY_TYPE PLUMBING
J 0
(-6525 4325);
DISPLAY 0.574468 (-6525 4325);
PAINT GREEN (-6525 4325);
DISPLAY INVISIBLE (-6525 4325);
FORCEPROP 1 LAST HDL_TAP TRUE
J 0
(-6200 4250);
DISPLAY 0.574468 (-6200 4250);
PAINT GREEN (-6200 4250);
DISPLAY INVISIBLE (-6200 4250);
FORCEPROP 1 LAST PATH I301
J 0
(-6527 4375);
DISPLAY 0.872340 (-6527 4375);
PAINT GREEN (-6527 4375);
DISPLAY INVISIBLE (-6527 4375);
FORCEADD TAP..6
(-6675 4525);
FORCEPROP 3 LASTPIN (-6625 4525) SIG_NAME GMI_CPU1_G2_CPU0_G0_TX_DN<11>
J 0
(-6615 4535);
DISPLAY 0.659574 (-6615 4535);
PAINT MONO (-6615 4535);
DISPLAY INVISIBLE (-6615 4535);
FORCEPROP 1 LASTPIN (-6625 4525) BN 11
J 0
(-6677 4533);
DISPLAY 0.489362 (-6677 4533);
PAINT MONO (-6677 4533);
FORCEPROP 2 LAST CDS_LIB standard
J 0
(-6675 4525);
DISPLAY INVISIBLE (-6675 4525);
FORCEPROP 1 LAST BODY_TYPE PLUMBING
J 0
(-6675 4475);
DISPLAY 0.574468 (-6675 4475);
PAINT GREEN (-6675 4475);
DISPLAY INVISIBLE (-6675 4475);
FORCEPROP 1 LAST HDL_TAP TRUE
J 0
(-6350 4400);
DISPLAY 0.574468 (-6350 4400);
PAINT GREEN (-6350 4400);
DISPLAY INVISIBLE (-6350 4400);
FORCEPROP 1 LAST PATH I302
J 0
(-6677 4525);
DISPLAY 0.872340 (-6677 4525);
PAINT GREEN (-6677 4525);
DISPLAY INVISIBLE (-6677 4525);
FORCEADD TAP..6
(-6675 4425);
FORCEPROP 3 LASTPIN (-6625 4425) SIG_NAME GMI_CPU1_G2_CPU0_G0_TX_DN<12>
J 0
(-6615 4435);
DISPLAY 0.659574 (-6615 4435);
PAINT MONO (-6615 4435);
DISPLAY INVISIBLE (-6615 4435);
FORCEPROP 1 LASTPIN (-6625 4425) BN 12
J 0
(-6677 4433);
DISPLAY 0.489362 (-6677 4433);
PAINT MONO (-6677 4433);
FORCEPROP 2 LAST CDS_LIB standard
J 0
(-6675 4425);
DISPLAY INVISIBLE (-6675 4425);
FORCEPROP 1 LAST BODY_TYPE PLUMBING
J 0
(-6675 4375);
DISPLAY 0.574468 (-6675 4375);
PAINT GREEN (-6675 4375);
DISPLAY INVISIBLE (-6675 4375);
FORCEPROP 1 LAST HDL_TAP TRUE
J 0
(-6350 4300);
DISPLAY 0.574468 (-6350 4300);
PAINT GREEN (-6350 4300);
DISPLAY INVISIBLE (-6350 4300);
FORCEPROP 1 LAST PATH I303
J 0
(-6677 4425);
DISPLAY 0.872340 (-6677 4425);
PAINT GREEN (-6677 4425);
DISPLAY INVISIBLE (-6677 4425);
FORCEADD TAP..6
(-6525 4275);
FORCEPROP 3 LASTPIN (-6475 4275) SIG_NAME GMI_CPU1_G2_CPU0_G0_TX_DP<14>
J 0
(-6465 4285);
DISPLAY 0.659574 (-6465 4285);
PAINT MONO (-6465 4285);
DISPLAY INVISIBLE (-6465 4285);
FORCEPROP 1 LASTPIN (-6475 4275) BN 14
J 0
(-6527 4283);
DISPLAY 0.489362 (-6527 4283);
PAINT MONO (-6527 4283);
FORCEPROP 2 LAST CDS_LIB standard
J 0
(-6525 4275);
DISPLAY INVISIBLE (-6525 4275);
FORCEPROP 1 LAST BODY_TYPE PLUMBING
J 0
(-6525 4225);
DISPLAY 0.574468 (-6525 4225);
PAINT GREEN (-6525 4225);
DISPLAY INVISIBLE (-6525 4225);
FORCEPROP 1 LAST HDL_TAP TRUE
J 0
(-6200 4150);
DISPLAY 0.574468 (-6200 4150);
PAINT GREEN (-6200 4150);
DISPLAY INVISIBLE (-6200 4150);
FORCEPROP 1 LAST PATH I304
J 0
(-6527 4275);
DISPLAY 0.872340 (-6527 4275);
PAINT GREEN (-6527 4275);
DISPLAY INVISIBLE (-6527 4275);
FORCEADD TAP..6
(-6525 4175);
FORCEPROP 3 LASTPIN (-6475 4175) SIG_NAME GMI_CPU1_G2_CPU0_G0_TX_DP<15>
J 0
(-6465 4185);
DISPLAY 0.659574 (-6465 4185);
PAINT MONO (-6465 4185);
DISPLAY INVISIBLE (-6465 4185);
FORCEPROP 1 LASTPIN (-6475 4175) BN 15
J 0
(-6527 4183);
DISPLAY 0.489362 (-6527 4183);
PAINT MONO (-6527 4183);
FORCEPROP 2 LAST CDS_LIB standard
J 0
(-6525 4175);
DISPLAY INVISIBLE (-6525 4175);
FORCEPROP 1 LAST BODY_TYPE PLUMBING
J 0
(-6525 4125);
DISPLAY 0.574468 (-6525 4125);
PAINT GREEN (-6525 4125);
DISPLAY INVISIBLE (-6525 4125);
FORCEPROP 1 LAST HDL_TAP TRUE
J 0
(-6200 4050);
DISPLAY 0.574468 (-6200 4050);
PAINT GREEN (-6200 4050);
DISPLAY INVISIBLE (-6200 4050);
FORCEPROP 1 LAST PATH I305
J 0
(-6527 4175);
DISPLAY 0.872340 (-6527 4175);
PAINT GREEN (-6527 4175);
DISPLAY INVISIBLE (-6527 4175);
FORCEADD TAP..6
(-6675 4325);
FORCEPROP 3 LASTPIN (-6625 4325) SIG_NAME GMI_CPU1_G2_CPU0_G0_TX_DN<13>
J 0
(-6615 4335);
DISPLAY 0.659574 (-6615 4335);
PAINT MONO (-6615 4335);
DISPLAY INVISIBLE (-6615 4335);
FORCEPROP 1 LASTPIN (-6625 4325) BN 13
J 0
(-6677 4333);
DISPLAY 0.489362 (-6677 4333);
PAINT MONO (-6677 4333);
FORCEPROP 2 LAST CDS_LIB standard
J 0
(-6675 4325);
DISPLAY INVISIBLE (-6675 4325);
FORCEPROP 1 LAST BODY_TYPE PLUMBING
J 0
(-6675 4275);
DISPLAY 0.574468 (-6675 4275);
PAINT GREEN (-6675 4275);
DISPLAY INVISIBLE (-6675 4275);
FORCEPROP 1 LAST HDL_TAP TRUE
J 0
(-6350 4200);
DISPLAY 0.574468 (-6350 4200);
PAINT GREEN (-6350 4200);
DISPLAY INVISIBLE (-6350 4200);
FORCEPROP 1 LAST PATH I306
J 0
(-6677 4325);
DISPLAY 0.872340 (-6677 4325);
PAINT GREEN (-6677 4325);
DISPLAY INVISIBLE (-6677 4325);
FORCEADD TAP..6
(-6675 4225);
FORCEPROP 3 LASTPIN (-6625 4225) SIG_NAME GMI_CPU1_G2_CPU0_G0_TX_DN<14>
J 0
(-6615 4235);
DISPLAY 0.659574 (-6615 4235);
PAINT MONO (-6615 4235);
DISPLAY INVISIBLE (-6615 4235);
FORCEPROP 1 LASTPIN (-6625 4225) BN 14
J 0
(-6677 4233);
DISPLAY 0.489362 (-6677 4233);
PAINT MONO (-6677 4233);
FORCEPROP 2 LAST CDS_LIB standard
J 0
(-6675 4225);
DISPLAY INVISIBLE (-6675 4225);
FORCEPROP 1 LAST BODY_TYPE PLUMBING
J 0
(-6675 4175);
DISPLAY 0.574468 (-6675 4175);
PAINT GREEN (-6675 4175);
DISPLAY INVISIBLE (-6675 4175);
FORCEPROP 1 LAST HDL_TAP TRUE
J 0
(-6350 4100);
DISPLAY 0.574468 (-6350 4100);
PAINT GREEN (-6350 4100);
DISPLAY INVISIBLE (-6350 4100);
FORCEPROP 1 LAST PATH I307
J 0
(-6677 4225);
DISPLAY 0.872340 (-6677 4225);
PAINT GREEN (-6677 4225);
DISPLAY INVISIBLE (-6677 4225);
FORCEADD TAP..6
(-6675 4125);
FORCEPROP 3 LASTPIN (-6625 4125) SIG_NAME GMI_CPU1_G2_CPU0_G0_TX_DN<15>
J 0
(-6615 4135);
DISPLAY 0.659574 (-6615 4135);
PAINT MONO (-6615 4135);
DISPLAY INVISIBLE (-6615 4135);
FORCEPROP 1 LASTPIN (-6625 4125) BN 15
J 0
(-6677 4133);
DISPLAY 0.489362 (-6677 4133);
PAINT MONO (-6677 4133);
FORCEPROP 2 LAST CDS_LIB standard
J 0
(-6675 4125);
DISPLAY INVISIBLE (-6675 4125);
FORCEPROP 1 LAST BODY_TYPE PLUMBING
J 0
(-6675 4075);
DISPLAY 0.574468 (-6675 4075);
PAINT GREEN (-6675 4075);
DISPLAY INVISIBLE (-6675 4075);
FORCEPROP 1 LAST HDL_TAP TRUE
J 0
(-6350 4000);
DISPLAY 0.574468 (-6350 4000);
PAINT GREEN (-6350 4000);
DISPLAY INVISIBLE (-6350 4000);
FORCEPROP 1 LAST PATH I308
J 0
(-6677 4125);
DISPLAY 0.872340 (-6677 4125);
PAINT GREEN (-6677 4125);
DISPLAY INVISIBLE (-6677 4125);
FORCEADD OFFPAGE..1
(-7775 5900);
FORCEPROP 2 LAST $XR0 50 
J 0
(-8026 5900);
DISPLAY 0.638298 (-8026 5900);
PAINT MONO (-8026 5900);
FORCEPROP 2 LAST CDS_LIB standard
J 0
(-7775 5900);
DISPLAY INVISIBLE (-7775 5900);
FORCEPROP 1 LAST OFFPAGE TRUE
J 0
(-7450 5775);
DISPLAY 0.872340 (-7450 5775);
PAINT GREEN (-7450 5775);
DISPLAY INVISIBLE (-7450 5775);
FORCEPROP 1 LAST COMMENT_BODY TRUE
J 0
(-7650 5800);
DISPLAY 0.872340 (-7650 5800);
PAINT GREEN (-7650 5800);
DISPLAY INVISIBLE (-7650 5800);
FORCEPROP 2 LAST PATH I309
J 0
(-8025 5950);
DISPLAY 1.021277 (-8025 5950);
DISPLAY INVISIBLE (-8025 5950);
FORCEADD OFFPAGE..1
(-7775 5850);
FORCEPROP 2 LAST $XR0 50 
J 0
(-8026 5850);
DISPLAY 0.638298 (-8026 5850);
PAINT MONO (-8026 5850);
FORCEPROP 2 LAST CDS_LIB standard
J 0
(-7775 5850);
DISPLAY INVISIBLE (-7775 5850);
FORCEPROP 1 LAST OFFPAGE TRUE
J 0
(-7450 5725);
DISPLAY 0.872340 (-7450 5725);
PAINT GREEN (-7450 5725);
DISPLAY INVISIBLE (-7450 5725);
FORCEPROP 1 LAST COMMENT_BODY TRUE
J 0
(-7650 5750);
DISPLAY 0.872340 (-7650 5750);
PAINT GREEN (-7650 5750);
DISPLAY INVISIBLE (-7650 5750);
FORCEPROP 2 LAST PATH I310
J 0
(-8025 5900);
DISPLAY 1.021277 (-8025 5900);
DISPLAY INVISIBLE (-8025 5900);
FORCEADD OFFPAGE..2
(-1975 3125);
FORCEPROP 2 LAST $XR0 50 
J 0
(-1786 3125);
DISPLAY 0.638298 (-1786 3125);
PAINT MONO (-1786 3125);
FORCEPROP 2 LAST CDS_LIB standard
J 0
(-1975 3125);
DISPLAY INVISIBLE (-1975 3125);
FORCEPROP 1 LAST OFFPAGE TRUE
J 0
(-1650 3000);
DISPLAY 0.872340 (-1650 3000);
PAINT GREEN (-1650 3000);
DISPLAY INVISIBLE (-1650 3000);
FORCEPROP 1 LAST COMMENT_BODY TRUE
J 0
(-2020 3030);
DISPLAY 0.872340 (-2020 3030);
PAINT GREEN (-2020 3030);
DISPLAY INVISIBLE (-2020 3030);
FORCEPROP 2 LAST PATH I311
J 0
(-1775 3175);
DISPLAY 1.021277 (-1775 3175);
DISPLAY INVISIBLE (-1775 3175);
FORCEADD OFFPAGE..2
(-1975 3175);
FORCEPROP 2 LAST $XR0 50 
J 0
(-1786 3175);
DISPLAY 0.638298 (-1786 3175);
PAINT MONO (-1786 3175);
FORCEPROP 2 LAST CDS_LIB standard
J 0
(-1975 3175);
DISPLAY INVISIBLE (-1975 3175);
FORCEPROP 1 LAST OFFPAGE TRUE
J 0
(-1650 3050);
DISPLAY 0.872340 (-1650 3050);
PAINT GREEN (-1650 3050);
DISPLAY INVISIBLE (-1650 3050);
FORCEPROP 1 LAST COMMENT_BODY TRUE
J 0
(-2020 3080);
DISPLAY 0.872340 (-2020 3080);
PAINT GREEN (-2020 3080);
DISPLAY INVISIBLE (-2020 3080);
FORCEPROP 2 LAST PATH I312
J 0
(-1775 3225);
DISPLAY 1.021277 (-1775 3225);
DISPLAY INVISIBLE (-1775 3225);
FORCEADD TAP..6
R 2
(-2950 2900);
FORCEPROP 3 LASTPIN (-3000 2900) SIG_NAME GMI_CPU0_G1_CPU1_G3_TX_DN<0>
J 0
(-2990 2910);
DISPLAY 0.659574 (-2990 2910);
PAINT MONO (-2990 2910);
DISPLAY INVISIBLE (-2990 2910);
FORCEPROP 1 LASTPIN (-3000 2900) BN 0
J 2
(-2948 2908);
DISPLAY 0.489362 (-2948 2908);
PAINT MONO (-2948 2908);
FORCEPROP 2 LAST CDS_LIB mstr_standard
J 0
(-2950 2900);
DISPLAY INVISIBLE (-2950 2900);
FORCEPROP 2 LAST BOM_COST IO_SLOT
J 0
(-3450 3000);
DISPLAY 0.829787 (-3450 3000);
DISPLAY INVISIBLE (-3450 3000);
FORCEPROP 1 LAST BODY_TYPE PLUMBING
J 2
(-2950 2850);
DISPLAY 0.702128 (-2950 2850);
PAINT GREEN (-2950 2850);
DISPLAY INVISIBLE (-2950 2850);
FORCEPROP 1 LAST HDL_TAP TRUE
J 2
(-3275 2775);
DISPLAY 0.702128 (-3275 2775);
PAINT GREEN (-3275 2775);
DISPLAY INVISIBLE (-3275 2775);
FORCEPROP 1 LAST PATH I313
J 2
(-2948 2900);
DISPLAY 0.872340 (-2948 2900);
PAINT GREEN (-2948 2900);
DISPLAY INVISIBLE (-2948 2900);
FORCEPROP 2 LAST ROOM RISER1
J 0
(-3450 2950);
DISPLAY 0.829787 (-3450 2950);
PAINT RED (-3450 2950);
DISPLAY INVISIBLE (-3450 2950);
FORCEADD TAP..6
R 2
(-3100 2850);
FORCEPROP 3 LASTPIN (-3150 2850) SIG_NAME GMI_CPU0_G1_CPU1_G3_TX_DP<1>
J 0
(-3140 2860);
DISPLAY 0.659574 (-3140 2860);
PAINT MONO (-3140 2860);
DISPLAY INVISIBLE (-3140 2860);
FORCEPROP 1 LASTPIN (-3150 2850) BN 1
J 2
(-3098 2858);
DISPLAY 0.489362 (-3098 2858);
PAINT MONO (-3098 2858);
FORCEPROP 2 LAST CDS_LIB mstr_standard
J 0
(-3100 2850);
DISPLAY INVISIBLE (-3100 2850);
FORCEPROP 2 LAST BOM_COST IO_SLOT
J 0
(-3600 2950);
DISPLAY 0.829787 (-3600 2950);
DISPLAY INVISIBLE (-3600 2950);
FORCEPROP 1 LAST BODY_TYPE PLUMBING
J 2
(-3100 2800);
DISPLAY 0.702128 (-3100 2800);
PAINT GREEN (-3100 2800);
DISPLAY INVISIBLE (-3100 2800);
FORCEPROP 1 LAST HDL_TAP TRUE
J 2
(-3425 2725);
DISPLAY 0.702128 (-3425 2725);
PAINT GREEN (-3425 2725);
DISPLAY INVISIBLE (-3425 2725);
FORCEPROP 1 LAST PATH I314
J 2
(-3098 2850);
DISPLAY 0.872340 (-3098 2850);
PAINT GREEN (-3098 2850);
DISPLAY INVISIBLE (-3098 2850);
FORCEPROP 2 LAST ROOM RISER1
J 0
(-3600 2900);
DISPLAY 0.829787 (-3600 2900);
PAINT RED (-3600 2900);
DISPLAY INVISIBLE (-3600 2900);
FORCEADD TAP..6
R 2
(-3100 2950);
FORCEPROP 3 LASTPIN (-3150 2950) SIG_NAME GMI_CPU0_G1_CPU1_G3_TX_DP<0>
J 0
(-3140 2960);
DISPLAY 0.659574 (-3140 2960);
PAINT MONO (-3140 2960);
DISPLAY INVISIBLE (-3140 2960);
FORCEPROP 1 LASTPIN (-3150 2950) BN 0
J 2
(-3098 2958);
DISPLAY 0.489362 (-3098 2958);
PAINT MONO (-3098 2958);
FORCEPROP 2 LAST BOM_COST IO_SLOT
J 0
(-3600 3050);
DISPLAY 0.829787 (-3600 3050);
DISPLAY INVISIBLE (-3600 3050);
FORCEPROP 2 LAST CDS_LIB mstr_standard
J 0
(-3100 2950);
DISPLAY INVISIBLE (-3100 2950);
FORCEPROP 1 LAST BODY_TYPE PLUMBING
J 2
(-3100 2900);
DISPLAY 0.702128 (-3100 2900);
PAINT GREEN (-3100 2900);
DISPLAY INVISIBLE (-3100 2900);
FORCEPROP 1 LAST HDL_TAP TRUE
J 2
(-3425 2825);
DISPLAY 0.702128 (-3425 2825);
PAINT GREEN (-3425 2825);
DISPLAY INVISIBLE (-3425 2825);
FORCEPROP 1 LAST PATH I315
J 2
(-3098 2950);
DISPLAY 0.872340 (-3098 2950);
PAINT GREEN (-3098 2950);
DISPLAY INVISIBLE (-3098 2950);
FORCEPROP 2 LAST ROOM RISER1
J 0
(-3600 3000);
DISPLAY 0.829787 (-3600 3000);
PAINT RED (-3600 3000);
DISPLAY INVISIBLE (-3600 3000);
FORCEADD TAP..6
R 2
(-2950 2800);
FORCEPROP 3 LASTPIN (-3000 2800) SIG_NAME GMI_CPU0_G1_CPU1_G3_TX_DN<1>
J 0
(-2990 2810);
DISPLAY 0.659574 (-2990 2810);
PAINT MONO (-2990 2810);
DISPLAY INVISIBLE (-2990 2810);
FORCEPROP 1 LASTPIN (-3000 2800) BN 1
J 2
(-2948 2808);
DISPLAY 0.489362 (-2948 2808);
PAINT MONO (-2948 2808);
FORCEPROP 2 LAST BOM_COST IO_SLOT
J 0
(-3450 2900);
DISPLAY 0.829787 (-3450 2900);
DISPLAY INVISIBLE (-3450 2900);
FORCEPROP 2 LAST CDS_LIB mstr_standard
J 0
(-2950 2800);
DISPLAY INVISIBLE (-2950 2800);
FORCEPROP 1 LAST BODY_TYPE PLUMBING
J 2
(-2950 2750);
DISPLAY 0.702128 (-2950 2750);
PAINT GREEN (-2950 2750);
DISPLAY INVISIBLE (-2950 2750);
FORCEPROP 1 LAST HDL_TAP TRUE
J 2
(-3275 2675);
DISPLAY 0.702128 (-3275 2675);
PAINT GREEN (-3275 2675);
DISPLAY INVISIBLE (-3275 2675);
FORCEPROP 1 LAST PATH I316
J 2
(-2948 2800);
DISPLAY 0.872340 (-2948 2800);
PAINT GREEN (-2948 2800);
DISPLAY INVISIBLE (-2948 2800);
FORCEPROP 2 LAST ROOM RISER1
J 0
(-3450 2850);
DISPLAY 0.829787 (-3450 2850);
PAINT RED (-3450 2850);
DISPLAY INVISIBLE (-3450 2850);
FORCEADD TAP..6
R 2
(-2950 2700);
FORCEPROP 3 LASTPIN (-3000 2700) SIG_NAME GMI_CPU0_G1_CPU1_G3_TX_DN<2>
J 0
(-2990 2710);
DISPLAY 0.659574 (-2990 2710);
PAINT MONO (-2990 2710);
DISPLAY INVISIBLE (-2990 2710);
FORCEPROP 1 LASTPIN (-3000 2700) BN 2
J 2
(-2948 2708);
DISPLAY 0.489362 (-2948 2708);
PAINT MONO (-2948 2708);
FORCEPROP 2 LAST BOM_COST IO_SLOT
J 0
(-3450 2800);
DISPLAY 0.829787 (-3450 2800);
DISPLAY INVISIBLE (-3450 2800);
FORCEPROP 2 LAST CDS_LIB standard
J 0
(-2950 2700);
DISPLAY INVISIBLE (-2950 2700);
FORCEPROP 1 LAST BODY_TYPE PLUMBING
J 2
(-2950 2650);
DISPLAY 0.702128 (-2950 2650);
PAINT GREEN (-2950 2650);
DISPLAY INVISIBLE (-2950 2650);
FORCEPROP 1 LAST HDL_TAP TRUE
J 2
(-3275 2575);
DISPLAY 0.702128 (-3275 2575);
PAINT GREEN (-3275 2575);
DISPLAY INVISIBLE (-3275 2575);
FORCEPROP 1 LAST PATH I317
J 2
(-2948 2700);
DISPLAY 0.872340 (-2948 2700);
PAINT GREEN (-2948 2700);
DISPLAY INVISIBLE (-2948 2700);
FORCEPROP 2 LAST ROOM RISER1
J 0
(-3450 2750);
DISPLAY 0.829787 (-3450 2750);
PAINT RED (-3450 2750);
DISPLAY INVISIBLE (-3450 2750);
FORCEADD TAP..6
R 2
(-2950 2600);
FORCEPROP 3 LASTPIN (-3000 2600) SIG_NAME GMI_CPU0_G1_CPU1_G3_TX_DN<3>
J 0
(-2990 2610);
DISPLAY 0.659574 (-2990 2610);
PAINT MONO (-2990 2610);
DISPLAY INVISIBLE (-2990 2610);
FORCEPROP 1 LASTPIN (-3000 2600) BN 3
J 2
(-2948 2608);
DISPLAY 0.489362 (-2948 2608);
PAINT MONO (-2948 2608);
FORCEPROP 2 LAST BOM_COST IO_SLOT
J 0
(-3450 2700);
DISPLAY 0.829787 (-3450 2700);
DISPLAY INVISIBLE (-3450 2700);
FORCEPROP 2 LAST CDS_LIB standard
J 0
(-2950 2600);
DISPLAY INVISIBLE (-2950 2600);
FORCEPROP 1 LAST BODY_TYPE PLUMBING
J 2
(-2950 2550);
DISPLAY 0.702128 (-2950 2550);
PAINT GREEN (-2950 2550);
DISPLAY INVISIBLE (-2950 2550);
FORCEPROP 1 LAST HDL_TAP TRUE
J 2
(-3275 2475);
DISPLAY 0.702128 (-3275 2475);
PAINT GREEN (-3275 2475);
DISPLAY INVISIBLE (-3275 2475);
FORCEPROP 1 LAST PATH I318
J 2
(-2948 2600);
DISPLAY 0.872340 (-2948 2600);
PAINT GREEN (-2948 2600);
DISPLAY INVISIBLE (-2948 2600);
FORCEPROP 2 LAST ROOM RISER1
J 0
(-3450 2650);
DISPLAY 0.829787 (-3450 2650);
PAINT RED (-3450 2650);
DISPLAY INVISIBLE (-3450 2650);
FORCEADD TAP..6
R 2
(-3100 2650);
FORCEPROP 3 LASTPIN (-3150 2650) SIG_NAME GMI_CPU0_G1_CPU1_G3_TX_DP<3>
J 0
(-3140 2660);
DISPLAY 0.659574 (-3140 2660);
PAINT MONO (-3140 2660);
DISPLAY INVISIBLE (-3140 2660);
FORCEPROP 1 LASTPIN (-3150 2650) BN 3
J 2
(-3098 2658);
DISPLAY 0.489362 (-3098 2658);
PAINT MONO (-3098 2658);
FORCEPROP 2 LAST CDS_LIB standard
J 0
(-3100 2650);
DISPLAY INVISIBLE (-3100 2650);
FORCEPROP 2 LAST BOM_COST IO_SLOT
J 0
(-3600 2750);
DISPLAY 0.829787 (-3600 2750);
DISPLAY INVISIBLE (-3600 2750);
FORCEPROP 1 LAST BODY_TYPE PLUMBING
J 2
(-3100 2600);
DISPLAY 0.702128 (-3100 2600);
PAINT GREEN (-3100 2600);
DISPLAY INVISIBLE (-3100 2600);
FORCEPROP 1 LAST HDL_TAP TRUE
J 2
(-3425 2525);
DISPLAY 0.702128 (-3425 2525);
PAINT GREEN (-3425 2525);
DISPLAY INVISIBLE (-3425 2525);
FORCEPROP 1 LAST PATH I319
J 2
(-3098 2650);
DISPLAY 0.872340 (-3098 2650);
PAINT GREEN (-3098 2650);
DISPLAY INVISIBLE (-3098 2650);
FORCEPROP 2 LAST ROOM RISER1
J 0
(-3600 2700);
DISPLAY 0.829787 (-3600 2700);
PAINT RED (-3600 2700);
DISPLAY INVISIBLE (-3600 2700);
FORCEADD TAP..6
R 2
(-3100 2750);
FORCEPROP 3 LASTPIN (-3150 2750) SIG_NAME GMI_CPU0_G1_CPU1_G3_TX_DP<2>
J 0
(-3140 2760);
DISPLAY 0.659574 (-3140 2760);
PAINT MONO (-3140 2760);
DISPLAY INVISIBLE (-3140 2760);
FORCEPROP 1 LASTPIN (-3150 2750) BN 2
J 2
(-3098 2758);
DISPLAY 0.489362 (-3098 2758);
PAINT MONO (-3098 2758);
FORCEPROP 2 LAST CDS_LIB standard
J 0
(-3100 2750);
DISPLAY INVISIBLE (-3100 2750);
FORCEPROP 2 LAST BOM_COST IO_SLOT
J 0
(-3600 2850);
DISPLAY 0.829787 (-3600 2850);
DISPLAY INVISIBLE (-3600 2850);
FORCEPROP 1 LAST BODY_TYPE PLUMBING
J 2
(-3100 2700);
DISPLAY 0.702128 (-3100 2700);
PAINT GREEN (-3100 2700);
DISPLAY INVISIBLE (-3100 2700);
FORCEPROP 1 LAST HDL_TAP TRUE
J 2
(-3425 2625);
DISPLAY 0.702128 (-3425 2625);
PAINT GREEN (-3425 2625);
DISPLAY INVISIBLE (-3425 2625);
FORCEPROP 1 LAST PATH I320
J 2
(-3098 2750);
DISPLAY 0.872340 (-3098 2750);
PAINT GREEN (-3098 2750);
DISPLAY INVISIBLE (-3098 2750);
FORCEPROP 2 LAST ROOM RISER1
J 0
(-3600 2800);
DISPLAY 0.829787 (-3600 2800);
PAINT RED (-3600 2800);
DISPLAY INVISIBLE (-3600 2800);
FORCEADD TAP..6
R 2
(-2950 2400);
FORCEPROP 3 LASTPIN (-3000 2400) SIG_NAME GMI_CPU0_G1_CPU1_G3_TX_DN<5>
J 0
(-2990 2410);
DISPLAY 0.659574 (-2990 2410);
PAINT MONO (-2990 2410);
DISPLAY INVISIBLE (-2990 2410);
FORCEPROP 1 LASTPIN (-3000 2400) BN 5
J 2
(-2948 2408);
DISPLAY 0.489362 (-2948 2408);
PAINT MONO (-2948 2408);
FORCEPROP 2 LAST BOM_COST IO_SLOT
J 0
(-3450 2500);
DISPLAY 0.829787 (-3450 2500);
DISPLAY INVISIBLE (-3450 2500);
FORCEPROP 2 LAST CDS_LIB standard
J 0
(-2950 2400);
DISPLAY INVISIBLE (-2950 2400);
FORCEPROP 1 LAST BODY_TYPE PLUMBING
J 2
(-2950 2350);
DISPLAY 0.702128 (-2950 2350);
PAINT GREEN (-2950 2350);
DISPLAY INVISIBLE (-2950 2350);
FORCEPROP 1 LAST HDL_TAP TRUE
J 2
(-3275 2275);
DISPLAY 0.702128 (-3275 2275);
PAINT GREEN (-3275 2275);
DISPLAY INVISIBLE (-3275 2275);
FORCEPROP 1 LAST PATH I321
J 2
(-2948 2400);
DISPLAY 0.872340 (-2948 2400);
PAINT GREEN (-2948 2400);
DISPLAY INVISIBLE (-2948 2400);
FORCEPROP 2 LAST ROOM RISER1
J 0
(-3450 2450);
DISPLAY 0.829787 (-3450 2450);
PAINT RED (-3450 2450);
DISPLAY INVISIBLE (-3450 2450);
FORCEADD TAP..6
R 2
(-2950 2500);
FORCEPROP 3 LASTPIN (-3000 2500) SIG_NAME GMI_CPU0_G1_CPU1_G3_TX_DN<4>
J 0
(-2990 2510);
DISPLAY 0.659574 (-2990 2510);
PAINT MONO (-2990 2510);
DISPLAY INVISIBLE (-2990 2510);
FORCEPROP 1 LASTPIN (-3000 2500) BN 4
J 2
(-2948 2508);
DISPLAY 0.489362 (-2948 2508);
PAINT MONO (-2948 2508);
FORCEPROP 2 LAST BOM_COST IO_SLOT
J 0
(-3450 2600);
DISPLAY 0.829787 (-3450 2600);
DISPLAY INVISIBLE (-3450 2600);
FORCEPROP 2 LAST CDS_LIB standard
J 0
(-2950 2500);
DISPLAY INVISIBLE (-2950 2500);
FORCEPROP 1 LAST BODY_TYPE PLUMBING
J 2
(-2950 2450);
DISPLAY 0.702128 (-2950 2450);
PAINT GREEN (-2950 2450);
DISPLAY INVISIBLE (-2950 2450);
FORCEPROP 1 LAST HDL_TAP TRUE
J 2
(-3275 2375);
DISPLAY 0.702128 (-3275 2375);
PAINT GREEN (-3275 2375);
DISPLAY INVISIBLE (-3275 2375);
FORCEPROP 1 LAST PATH I322
J 2
(-2948 2500);
DISPLAY 0.872340 (-2948 2500);
PAINT GREEN (-2948 2500);
DISPLAY INVISIBLE (-2948 2500);
FORCEPROP 2 LAST ROOM RISER1
J 0
(-3450 2550);
DISPLAY 0.829787 (-3450 2550);
PAINT RED (-3450 2550);
DISPLAY INVISIBLE (-3450 2550);
FORCEADD TAP..6
R 2
(-3100 2350);
FORCEPROP 3 LASTPIN (-3150 2350) SIG_NAME GMI_CPU0_G1_CPU1_G3_TX_DP<6>
J 0
(-3140 2360);
DISPLAY 0.659574 (-3140 2360);
PAINT MONO (-3140 2360);
DISPLAY INVISIBLE (-3140 2360);
FORCEPROP 1 LASTPIN (-3150 2350) BN 6
J 2
(-3098 2358);
DISPLAY 0.489362 (-3098 2358);
PAINT MONO (-3098 2358);
FORCEPROP 2 LAST CDS_LIB standard
J 0
(-3100 2350);
DISPLAY INVISIBLE (-3100 2350);
FORCEPROP 2 LAST BOM_COST IO_SLOT
J 0
(-3600 2450);
DISPLAY 0.829787 (-3600 2450);
DISPLAY INVISIBLE (-3600 2450);
FORCEPROP 1 LAST BODY_TYPE PLUMBING
J 2
(-3100 2300);
DISPLAY 0.702128 (-3100 2300);
PAINT GREEN (-3100 2300);
DISPLAY INVISIBLE (-3100 2300);
FORCEPROP 1 LAST HDL_TAP TRUE
J 2
(-3425 2225);
DISPLAY 0.702128 (-3425 2225);
PAINT GREEN (-3425 2225);
DISPLAY INVISIBLE (-3425 2225);
FORCEPROP 1 LAST PATH I323
J 2
(-3098 2350);
DISPLAY 0.872340 (-3098 2350);
PAINT GREEN (-3098 2350);
DISPLAY INVISIBLE (-3098 2350);
FORCEPROP 2 LAST ROOM RISER1
J 0
(-3600 2400);
DISPLAY 0.829787 (-3600 2400);
PAINT RED (-3600 2400);
DISPLAY INVISIBLE (-3600 2400);
FORCEADD TAP..6
R 2
(-3100 2450);
FORCEPROP 3 LASTPIN (-3150 2450) SIG_NAME GMI_CPU0_G1_CPU1_G3_TX_DP<5>
J 0
(-3140 2460);
DISPLAY 0.659574 (-3140 2460);
PAINT MONO (-3140 2460);
DISPLAY INVISIBLE (-3140 2460);
FORCEPROP 1 LASTPIN (-3150 2450) BN 5
J 2
(-3098 2458);
DISPLAY 0.489362 (-3098 2458);
PAINT MONO (-3098 2458);
FORCEPROP 2 LAST CDS_LIB standard
J 0
(-3100 2450);
DISPLAY INVISIBLE (-3100 2450);
FORCEPROP 2 LAST BOM_COST IO_SLOT
J 0
(-3600 2550);
DISPLAY 0.829787 (-3600 2550);
DISPLAY INVISIBLE (-3600 2550);
FORCEPROP 1 LAST BODY_TYPE PLUMBING
J 2
(-3100 2400);
DISPLAY 0.702128 (-3100 2400);
PAINT GREEN (-3100 2400);
DISPLAY INVISIBLE (-3100 2400);
FORCEPROP 1 LAST HDL_TAP TRUE
J 2
(-3425 2325);
DISPLAY 0.702128 (-3425 2325);
PAINT GREEN (-3425 2325);
DISPLAY INVISIBLE (-3425 2325);
FORCEPROP 1 LAST PATH I324
J 2
(-3098 2450);
DISPLAY 0.872340 (-3098 2450);
PAINT GREEN (-3098 2450);
DISPLAY INVISIBLE (-3098 2450);
FORCEPROP 2 LAST ROOM RISER1
J 0
(-3600 2500);
DISPLAY 0.829787 (-3600 2500);
PAINT RED (-3600 2500);
DISPLAY INVISIBLE (-3600 2500);
FORCEADD TAP..6
R 2
(-3100 2550);
FORCEPROP 3 LASTPIN (-3150 2550) SIG_NAME GMI_CPU0_G1_CPU1_G3_TX_DP<4>
J 0
(-3140 2560);
DISPLAY 0.659574 (-3140 2560);
PAINT MONO (-3140 2560);
DISPLAY INVISIBLE (-3140 2560);
FORCEPROP 1 LASTPIN (-3150 2550) BN 4
J 2
(-3098 2558);
DISPLAY 0.489362 (-3098 2558);
PAINT MONO (-3098 2558);
FORCEPROP 2 LAST CDS_LIB standard
J 0
(-3100 2550);
DISPLAY INVISIBLE (-3100 2550);
FORCEPROP 2 LAST BOM_COST IO_SLOT
J 0
(-3600 2650);
DISPLAY 0.829787 (-3600 2650);
DISPLAY INVISIBLE (-3600 2650);
FORCEPROP 1 LAST BODY_TYPE PLUMBING
J 2
(-3100 2500);
DISPLAY 0.702128 (-3100 2500);
PAINT GREEN (-3100 2500);
DISPLAY INVISIBLE (-3100 2500);
FORCEPROP 1 LAST HDL_TAP TRUE
J 2
(-3425 2425);
DISPLAY 0.702128 (-3425 2425);
PAINT GREEN (-3425 2425);
DISPLAY INVISIBLE (-3425 2425);
FORCEPROP 1 LAST PATH I325
J 2
(-3098 2550);
DISPLAY 0.872340 (-3098 2550);
PAINT GREEN (-3098 2550);
DISPLAY INVISIBLE (-3098 2550);
FORCEPROP 2 LAST ROOM RISER1
J 0
(-3600 2600);
DISPLAY 0.829787 (-3600 2600);
PAINT RED (-3600 2600);
DISPLAY INVISIBLE (-3600 2600);
FORCEADD TAP..6
R 2
(-2950 2200);
FORCEPROP 3 LASTPIN (-3000 2200) SIG_NAME GMI_CPU0_G1_CPU1_G3_TX_DN<7>
J 0
(-2990 2210);
DISPLAY 0.659574 (-2990 2210);
PAINT MONO (-2990 2210);
DISPLAY INVISIBLE (-2990 2210);
FORCEPROP 1 LASTPIN (-3000 2200) BN 7
J 2
(-2948 2208);
DISPLAY 0.489362 (-2948 2208);
PAINT MONO (-2948 2208);
FORCEPROP 2 LAST BOM_COST IO_SLOT
J 0
(-3450 2300);
DISPLAY 0.829787 (-3450 2300);
DISPLAY INVISIBLE (-3450 2300);
FORCEPROP 2 LAST CDS_LIB standard
J 0
(-2950 2200);
DISPLAY INVISIBLE (-2950 2200);
FORCEPROP 1 LAST BODY_TYPE PLUMBING
J 2
(-2950 2150);
DISPLAY 0.702128 (-2950 2150);
PAINT GREEN (-2950 2150);
DISPLAY INVISIBLE (-2950 2150);
FORCEPROP 1 LAST HDL_TAP TRUE
J 2
(-3275 2075);
DISPLAY 0.702128 (-3275 2075);
PAINT GREEN (-3275 2075);
DISPLAY INVISIBLE (-3275 2075);
FORCEPROP 1 LAST PATH I326
J 2
(-2948 2200);
DISPLAY 0.872340 (-2948 2200);
PAINT GREEN (-2948 2200);
DISPLAY INVISIBLE (-2948 2200);
FORCEPROP 2 LAST ROOM RISER1
J 0
(-3450 2250);
DISPLAY 0.829787 (-3450 2250);
PAINT RED (-3450 2250);
DISPLAY INVISIBLE (-3450 2250);
FORCEADD TAP..6
R 2
(-2950 2300);
FORCEPROP 3 LASTPIN (-3000 2300) SIG_NAME GMI_CPU0_G1_CPU1_G3_TX_DN<6>
J 0
(-2990 2310);
DISPLAY 0.659574 (-2990 2310);
PAINT MONO (-2990 2310);
DISPLAY INVISIBLE (-2990 2310);
FORCEPROP 1 LASTPIN (-3000 2300) BN 6
J 2
(-2948 2308);
DISPLAY 0.489362 (-2948 2308);
PAINT MONO (-2948 2308);
FORCEPROP 2 LAST BOM_COST IO_SLOT
J 0
(-3450 2400);
DISPLAY 0.829787 (-3450 2400);
DISPLAY INVISIBLE (-3450 2400);
FORCEPROP 2 LAST CDS_LIB standard
J 0
(-2950 2300);
DISPLAY INVISIBLE (-2950 2300);
FORCEPROP 1 LAST BODY_TYPE PLUMBING
J 2
(-2950 2250);
DISPLAY 0.702128 (-2950 2250);
PAINT GREEN (-2950 2250);
DISPLAY INVISIBLE (-2950 2250);
FORCEPROP 1 LAST HDL_TAP TRUE
J 2
(-3275 2175);
DISPLAY 0.702128 (-3275 2175);
PAINT GREEN (-3275 2175);
DISPLAY INVISIBLE (-3275 2175);
FORCEPROP 1 LAST PATH I327
J 2
(-2948 2300);
DISPLAY 0.872340 (-2948 2300);
PAINT GREEN (-2948 2300);
DISPLAY INVISIBLE (-2948 2300);
FORCEPROP 2 LAST ROOM RISER1
J 0
(-3450 2350);
DISPLAY 0.829787 (-3450 2350);
PAINT RED (-3450 2350);
DISPLAY INVISIBLE (-3450 2350);
FORCEADD TAP..6
R 2
(-2950 2100);
FORCEPROP 3 LASTPIN (-3000 2100) SIG_NAME GMI_CPU0_G1_CPU1_G3_TX_DN<8>
J 0
(-2990 2110);
DISPLAY 0.659574 (-2990 2110);
PAINT MONO (-2990 2110);
DISPLAY INVISIBLE (-2990 2110);
FORCEPROP 1 LASTPIN (-3000 2100) BN 8
J 2
(-2948 2108);
DISPLAY 0.489362 (-2948 2108);
PAINT MONO (-2948 2108);
FORCEPROP 2 LAST BOM_COST IO_SLOT
J 0
(-3450 2200);
DISPLAY 0.829787 (-3450 2200);
DISPLAY INVISIBLE (-3450 2200);
FORCEPROP 2 LAST CDS_LIB standard
J 0
(-2950 2100);
DISPLAY INVISIBLE (-2950 2100);
FORCEPROP 1 LAST BODY_TYPE PLUMBING
J 2
(-2950 2050);
DISPLAY 0.702128 (-2950 2050);
PAINT GREEN (-2950 2050);
DISPLAY INVISIBLE (-2950 2050);
FORCEPROP 1 LAST HDL_TAP TRUE
J 2
(-3275 1975);
DISPLAY 0.702128 (-3275 1975);
PAINT GREEN (-3275 1975);
DISPLAY INVISIBLE (-3275 1975);
FORCEPROP 1 LAST PATH I328
J 2
(-2948 2100);
DISPLAY 0.872340 (-2948 2100);
PAINT GREEN (-2948 2100);
DISPLAY INVISIBLE (-2948 2100);
FORCEPROP 2 LAST ROOM RISER1
J 0
(-3450 2150);
DISPLAY 0.829787 (-3450 2150);
PAINT RED (-3450 2150);
DISPLAY INVISIBLE (-3450 2150);
FORCEADD TAP..6
R 2
(-3100 2150);
FORCEPROP 3 LASTPIN (-3150 2150) SIG_NAME GMI_CPU0_G1_CPU1_G3_TX_DP<8>
J 0
(-3140 2160);
DISPLAY 0.659574 (-3140 2160);
PAINT MONO (-3140 2160);
DISPLAY INVISIBLE (-3140 2160);
FORCEPROP 1 LASTPIN (-3150 2150) BN 8
J 2
(-3098 2158);
DISPLAY 0.489362 (-3098 2158);
PAINT MONO (-3098 2158);
FORCEPROP 2 LAST CDS_LIB standard
J 0
(-3100 2150);
DISPLAY INVISIBLE (-3100 2150);
FORCEPROP 2 LAST BOM_COST IO_SLOT
J 0
(-3600 2250);
DISPLAY 0.829787 (-3600 2250);
DISPLAY INVISIBLE (-3600 2250);
FORCEPROP 1 LAST BODY_TYPE PLUMBING
J 2
(-3100 2100);
DISPLAY 0.702128 (-3100 2100);
PAINT GREEN (-3100 2100);
DISPLAY INVISIBLE (-3100 2100);
FORCEPROP 1 LAST HDL_TAP TRUE
J 2
(-3425 2025);
DISPLAY 0.702128 (-3425 2025);
PAINT GREEN (-3425 2025);
DISPLAY INVISIBLE (-3425 2025);
FORCEPROP 1 LAST PATH I329
J 2
(-3098 2150);
DISPLAY 0.872340 (-3098 2150);
PAINT GREEN (-3098 2150);
DISPLAY INVISIBLE (-3098 2150);
FORCEPROP 2 LAST ROOM RISER1
J 0
(-3600 2200);
DISPLAY 0.829787 (-3600 2200);
PAINT RED (-3600 2200);
DISPLAY INVISIBLE (-3600 2200);
FORCEADD TAP..6
R 2
(-3100 2050);
FORCEPROP 3 LASTPIN (-3150 2050) SIG_NAME GMI_CPU0_G1_CPU1_G3_TX_DP<9>
J 0
(-3140 2060);
DISPLAY 0.659574 (-3140 2060);
PAINT MONO (-3140 2060);
DISPLAY INVISIBLE (-3140 2060);
FORCEPROP 1 LASTPIN (-3150 2050) BN 9
J 2
(-3098 2058);
DISPLAY 0.489362 (-3098 2058);
PAINT MONO (-3098 2058);
FORCEPROP 2 LAST CDS_LIB standard
J 0
(-3100 2050);
DISPLAY INVISIBLE (-3100 2050);
FORCEPROP 2 LAST BOM_COST IO_SLOT
J 0
(-3600 2150);
DISPLAY 0.829787 (-3600 2150);
DISPLAY INVISIBLE (-3600 2150);
FORCEPROP 1 LAST BODY_TYPE PLUMBING
J 2
(-3100 2000);
DISPLAY 0.702128 (-3100 2000);
PAINT GREEN (-3100 2000);
DISPLAY INVISIBLE (-3100 2000);
FORCEPROP 1 LAST HDL_TAP TRUE
J 2
(-3425 1925);
DISPLAY 0.702128 (-3425 1925);
PAINT GREEN (-3425 1925);
DISPLAY INVISIBLE (-3425 1925);
FORCEPROP 1 LAST PATH I330
J 2
(-3098 2050);
DISPLAY 0.872340 (-3098 2050);
PAINT GREEN (-3098 2050);
DISPLAY INVISIBLE (-3098 2050);
FORCEPROP 2 LAST ROOM RISER1
J 0
(-3600 2100);
DISPLAY 0.829787 (-3600 2100);
PAINT RED (-3600 2100);
DISPLAY INVISIBLE (-3600 2100);
FORCEADD TAP..6
R 2
(-3100 2250);
FORCEPROP 3 LASTPIN (-3150 2250) SIG_NAME GMI_CPU0_G1_CPU1_G3_TX_DP<7>
J 0
(-3140 2260);
DISPLAY 0.659574 (-3140 2260);
PAINT MONO (-3140 2260);
DISPLAY INVISIBLE (-3140 2260);
FORCEPROP 1 LASTPIN (-3150 2250) BN 7
J 2
(-3098 2258);
DISPLAY 0.489362 (-3098 2258);
PAINT MONO (-3098 2258);
FORCEPROP 2 LAST CDS_LIB standard
J 0
(-3100 2250);
DISPLAY INVISIBLE (-3100 2250);
FORCEPROP 2 LAST BOM_COST IO_SLOT
J 0
(-3600 2350);
DISPLAY 0.829787 (-3600 2350);
DISPLAY INVISIBLE (-3600 2350);
FORCEPROP 1 LAST BODY_TYPE PLUMBING
J 2
(-3100 2200);
DISPLAY 0.702128 (-3100 2200);
PAINT GREEN (-3100 2200);
DISPLAY INVISIBLE (-3100 2200);
FORCEPROP 1 LAST HDL_TAP TRUE
J 2
(-3425 2125);
DISPLAY 0.702128 (-3425 2125);
PAINT GREEN (-3425 2125);
DISPLAY INVISIBLE (-3425 2125);
FORCEPROP 1 LAST PATH I331
J 2
(-3098 2250);
DISPLAY 0.872340 (-3098 2250);
PAINT GREEN (-3098 2250);
DISPLAY INVISIBLE (-3098 2250);
FORCEPROP 2 LAST ROOM RISER1
J 0
(-3600 2300);
DISPLAY 0.829787 (-3600 2300);
PAINT RED (-3600 2300);
DISPLAY INVISIBLE (-3600 2300);
FORCEADD TAP..6
R 2
(-2950 2000);
FORCEPROP 3 LASTPIN (-3000 2000) SIG_NAME GMI_CPU0_G1_CPU1_G3_TX_DN<9>
J 0
(-2990 2010);
DISPLAY 0.659574 (-2990 2010);
PAINT MONO (-2990 2010);
DISPLAY INVISIBLE (-2990 2010);
FORCEPROP 1 LASTPIN (-3000 2000) BN 9
J 2
(-2948 2008);
DISPLAY 0.489362 (-2948 2008);
PAINT MONO (-2948 2008);
FORCEPROP 2 LAST BOM_COST IO_SLOT
J 0
(-3450 2100);
DISPLAY 0.829787 (-3450 2100);
DISPLAY INVISIBLE (-3450 2100);
FORCEPROP 2 LAST CDS_LIB standard
J 0
(-2950 2000);
DISPLAY INVISIBLE (-2950 2000);
FORCEPROP 1 LAST BODY_TYPE PLUMBING
J 2
(-2950 1950);
DISPLAY 0.702128 (-2950 1950);
PAINT GREEN (-2950 1950);
DISPLAY INVISIBLE (-2950 1950);
FORCEPROP 1 LAST HDL_TAP TRUE
J 2
(-3275 1875);
DISPLAY 0.702128 (-3275 1875);
PAINT GREEN (-3275 1875);
DISPLAY INVISIBLE (-3275 1875);
FORCEPROP 1 LAST PATH I332
J 2
(-2948 2000);
DISPLAY 0.872340 (-2948 2000);
PAINT GREEN (-2948 2000);
DISPLAY INVISIBLE (-2948 2000);
FORCEPROP 2 LAST ROOM RISER1
J 0
(-3450 2050);
DISPLAY 0.829787 (-3450 2050);
PAINT RED (-3450 2050);
DISPLAY INVISIBLE (-3450 2050);
FORCEADD TAP..6
R 2
(-2950 1900);
FORCEPROP 3 LASTPIN (-3000 1900) SIG_NAME GMI_CPU0_G1_CPU1_G3_TX_DN<10>
J 0
(-2990 1910);
DISPLAY 0.659574 (-2990 1910);
PAINT MONO (-2990 1910);
DISPLAY INVISIBLE (-2990 1910);
FORCEPROP 1 LASTPIN (-3000 1900) BN 10
J 2
(-2948 1908);
DISPLAY 0.489362 (-2948 1908);
PAINT MONO (-2948 1908);
FORCEPROP 2 LAST BOM_COST IO_SLOT
J 0
(-3450 2000);
DISPLAY 0.829787 (-3450 2000);
DISPLAY INVISIBLE (-3450 2000);
FORCEPROP 2 LAST CDS_LIB standard
J 0
(-2950 1900);
DISPLAY INVISIBLE (-2950 1900);
FORCEPROP 1 LAST BODY_TYPE PLUMBING
J 2
(-2950 1850);
DISPLAY 0.702128 (-2950 1850);
PAINT GREEN (-2950 1850);
DISPLAY INVISIBLE (-2950 1850);
FORCEPROP 1 LAST HDL_TAP TRUE
J 2
(-3275 1775);
DISPLAY 0.702128 (-3275 1775);
PAINT GREEN (-3275 1775);
DISPLAY INVISIBLE (-3275 1775);
FORCEPROP 1 LAST PATH I333
J 2
(-2948 1900);
DISPLAY 0.872340 (-2948 1900);
PAINT GREEN (-2948 1900);
DISPLAY INVISIBLE (-2948 1900);
FORCEPROP 2 LAST ROOM RISER1
J 0
(-3450 1950);
DISPLAY 0.829787 (-3450 1950);
PAINT RED (-3450 1950);
DISPLAY INVISIBLE (-3450 1950);
FORCEADD TAP..6
R 2
(-2950 1800);
FORCEPROP 3 LASTPIN (-3000 1800) SIG_NAME GMI_CPU0_G1_CPU1_G3_TX_DN<11>
J 0
(-2990 1810);
DISPLAY 0.659574 (-2990 1810);
PAINT MONO (-2990 1810);
DISPLAY INVISIBLE (-2990 1810);
FORCEPROP 1 LASTPIN (-3000 1800) BN 11
J 2
(-2948 1808);
DISPLAY 0.489362 (-2948 1808);
PAINT MONO (-2948 1808);
FORCEPROP 2 LAST BOM_COST IO_SLOT
J 0
(-3450 1900);
DISPLAY 0.829787 (-3450 1900);
DISPLAY INVISIBLE (-3450 1900);
FORCEPROP 2 LAST CDS_LIB standard
J 0
(-2950 1800);
DISPLAY INVISIBLE (-2950 1800);
FORCEPROP 1 LAST BODY_TYPE PLUMBING
J 2
(-2950 1750);
DISPLAY 0.702128 (-2950 1750);
PAINT GREEN (-2950 1750);
DISPLAY INVISIBLE (-2950 1750);
FORCEPROP 1 LAST HDL_TAP TRUE
J 2
(-3275 1675);
DISPLAY 0.702128 (-3275 1675);
PAINT GREEN (-3275 1675);
DISPLAY INVISIBLE (-3275 1675);
FORCEPROP 1 LAST PATH I334
J 2
(-2948 1800);
DISPLAY 0.872340 (-2948 1800);
PAINT GREEN (-2948 1800);
DISPLAY INVISIBLE (-2948 1800);
FORCEPROP 2 LAST ROOM RISER1
J 0
(-3450 1850);
DISPLAY 0.829787 (-3450 1850);
PAINT RED (-3450 1850);
DISPLAY INVISIBLE (-3450 1850);
FORCEADD TAP..6
R 2
(-3100 1850);
FORCEPROP 3 LASTPIN (-3150 1850) SIG_NAME GMI_CPU0_G1_CPU1_G3_TX_DP<11>
J 0
(-3140 1860);
DISPLAY 0.659574 (-3140 1860);
PAINT MONO (-3140 1860);
DISPLAY INVISIBLE (-3140 1860);
FORCEPROP 1 LASTPIN (-3150 1850) BN 11
J 2
(-3098 1858);
DISPLAY 0.489362 (-3098 1858);
PAINT MONO (-3098 1858);
FORCEPROP 2 LAST CDS_LIB standard
J 0
(-3100 1850);
DISPLAY INVISIBLE (-3100 1850);
FORCEPROP 2 LAST BOM_COST IO_SLOT
J 0
(-3600 1950);
DISPLAY 0.829787 (-3600 1950);
DISPLAY INVISIBLE (-3600 1950);
FORCEPROP 1 LAST BODY_TYPE PLUMBING
J 2
(-3100 1800);
DISPLAY 0.702128 (-3100 1800);
PAINT GREEN (-3100 1800);
DISPLAY INVISIBLE (-3100 1800);
FORCEPROP 1 LAST HDL_TAP TRUE
J 2
(-3425 1725);
DISPLAY 0.702128 (-3425 1725);
PAINT GREEN (-3425 1725);
DISPLAY INVISIBLE (-3425 1725);
FORCEPROP 1 LAST PATH I335
J 2
(-3098 1850);
DISPLAY 0.872340 (-3098 1850);
PAINT GREEN (-3098 1850);
DISPLAY INVISIBLE (-3098 1850);
FORCEPROP 2 LAST ROOM RISER1
J 0
(-3600 1900);
DISPLAY 0.829787 (-3600 1900);
PAINT RED (-3600 1900);
DISPLAY INVISIBLE (-3600 1900);
FORCEADD TAP..6
R 2
(-3100 1950);
FORCEPROP 3 LASTPIN (-3150 1950) SIG_NAME GMI_CPU0_G1_CPU1_G3_TX_DP<10>
J 0
(-3140 1960);
DISPLAY 0.659574 (-3140 1960);
PAINT MONO (-3140 1960);
DISPLAY INVISIBLE (-3140 1960);
FORCEPROP 1 LASTPIN (-3150 1950) BN 10
J 2
(-3098 1958);
DISPLAY 0.489362 (-3098 1958);
PAINT MONO (-3098 1958);
FORCEPROP 2 LAST CDS_LIB standard
J 0
(-3100 1950);
DISPLAY INVISIBLE (-3100 1950);
FORCEPROP 2 LAST BOM_COST IO_SLOT
J 0
(-3600 2050);
DISPLAY 0.829787 (-3600 2050);
DISPLAY INVISIBLE (-3600 2050);
FORCEPROP 1 LAST BODY_TYPE PLUMBING
J 2
(-3100 1900);
DISPLAY 0.702128 (-3100 1900);
PAINT GREEN (-3100 1900);
DISPLAY INVISIBLE (-3100 1900);
FORCEPROP 1 LAST HDL_TAP TRUE
J 2
(-3425 1825);
DISPLAY 0.702128 (-3425 1825);
PAINT GREEN (-3425 1825);
DISPLAY INVISIBLE (-3425 1825);
FORCEPROP 1 LAST PATH I336
J 2
(-3098 1950);
DISPLAY 0.872340 (-3098 1950);
PAINT GREEN (-3098 1950);
DISPLAY INVISIBLE (-3098 1950);
FORCEPROP 2 LAST ROOM RISER1
J 0
(-3600 2000);
DISPLAY 0.829787 (-3600 2000);
PAINT RED (-3600 2000);
DISPLAY INVISIBLE (-3600 2000);
FORCEADD TAP..6
R 2
(-2950 1700);
FORCEPROP 3 LASTPIN (-3000 1700) SIG_NAME GMI_CPU0_G1_CPU1_G3_TX_DN<12>
J 0
(-2990 1710);
DISPLAY 0.659574 (-2990 1710);
PAINT MONO (-2990 1710);
DISPLAY INVISIBLE (-2990 1710);
FORCEPROP 1 LASTPIN (-3000 1700) BN 12
J 2
(-2948 1708);
DISPLAY 0.489362 (-2948 1708);
PAINT MONO (-2948 1708);
FORCEPROP 2 LAST BOM_COST IO_SLOT
J 0
(-3450 1800);
DISPLAY 0.829787 (-3450 1800);
DISPLAY INVISIBLE (-3450 1800);
FORCEPROP 2 LAST CDS_LIB standard
J 0
(-2950 1700);
DISPLAY INVISIBLE (-2950 1700);
FORCEPROP 1 LAST BODY_TYPE PLUMBING
J 2
(-2950 1650);
DISPLAY 0.702128 (-2950 1650);
PAINT GREEN (-2950 1650);
DISPLAY INVISIBLE (-2950 1650);
FORCEPROP 1 LAST HDL_TAP TRUE
J 2
(-3275 1575);
DISPLAY 0.702128 (-3275 1575);
PAINT GREEN (-3275 1575);
DISPLAY INVISIBLE (-3275 1575);
FORCEPROP 1 LAST PATH I337
J 2
(-2948 1700);
DISPLAY 0.872340 (-2948 1700);
PAINT GREEN (-2948 1700);
DISPLAY INVISIBLE (-2948 1700);
FORCEPROP 2 LAST ROOM RISER1
J 0
(-3450 1750);
DISPLAY 0.829787 (-3450 1750);
PAINT RED (-3450 1750);
DISPLAY INVISIBLE (-3450 1750);
FORCEADD TAP..6
R 2
(-2950 1600);
FORCEPROP 3 LASTPIN (-3000 1600) SIG_NAME GMI_CPU0_G1_CPU1_G3_TX_DN<13>
J 0
(-2990 1610);
DISPLAY 0.659574 (-2990 1610);
PAINT MONO (-2990 1610);
DISPLAY INVISIBLE (-2990 1610);
FORCEPROP 1 LASTPIN (-3000 1600) BN 13
J 2
(-2948 1608);
DISPLAY 0.489362 (-2948 1608);
PAINT MONO (-2948 1608);
FORCEPROP 2 LAST BOM_COST IO_SLOT
J 0
(-3450 1700);
DISPLAY 0.829787 (-3450 1700);
DISPLAY INVISIBLE (-3450 1700);
FORCEPROP 2 LAST CDS_LIB standard
J 0
(-2950 1600);
DISPLAY INVISIBLE (-2950 1600);
FORCEPROP 1 LAST BODY_TYPE PLUMBING
J 2
(-2950 1550);
DISPLAY 0.702128 (-2950 1550);
PAINT GREEN (-2950 1550);
DISPLAY INVISIBLE (-2950 1550);
FORCEPROP 1 LAST HDL_TAP TRUE
J 2
(-3275 1475);
DISPLAY 0.702128 (-3275 1475);
PAINT GREEN (-3275 1475);
DISPLAY INVISIBLE (-3275 1475);
FORCEPROP 1 LAST PATH I338
J 2
(-2948 1600);
DISPLAY 0.872340 (-2948 1600);
PAINT GREEN (-2948 1600);
DISPLAY INVISIBLE (-2948 1600);
FORCEPROP 2 LAST ROOM RISER1
J 0
(-3450 1650);
DISPLAY 0.829787 (-3450 1650);
PAINT RED (-3450 1650);
DISPLAY INVISIBLE (-3450 1650);
FORCEADD TAP..6
R 2
(-3100 1550);
FORCEPROP 3 LASTPIN (-3150 1550) SIG_NAME GMI_CPU0_G1_CPU1_G3_TX_DP<14>
J 0
(-3140 1560);
DISPLAY 0.659574 (-3140 1560);
PAINT MONO (-3140 1560);
DISPLAY INVISIBLE (-3140 1560);
FORCEPROP 1 LASTPIN (-3150 1550) BN 14
J 2
(-3098 1558);
DISPLAY 0.489362 (-3098 1558);
PAINT MONO (-3098 1558);
FORCEPROP 2 LAST CDS_LIB standard
J 0
(-3100 1550);
DISPLAY INVISIBLE (-3100 1550);
FORCEPROP 2 LAST BOM_COST IO_SLOT
J 0
(-3600 1650);
DISPLAY 0.829787 (-3600 1650);
DISPLAY INVISIBLE (-3600 1650);
FORCEPROP 1 LAST BODY_TYPE PLUMBING
J 2
(-3100 1500);
DISPLAY 0.702128 (-3100 1500);
PAINT GREEN (-3100 1500);
DISPLAY INVISIBLE (-3100 1500);
FORCEPROP 1 LAST HDL_TAP TRUE
J 2
(-3425 1425);
DISPLAY 0.702128 (-3425 1425);
PAINT GREEN (-3425 1425);
DISPLAY INVISIBLE (-3425 1425);
FORCEPROP 1 LAST PATH I339
J 2
(-3098 1550);
DISPLAY 0.872340 (-3098 1550);
PAINT GREEN (-3098 1550);
DISPLAY INVISIBLE (-3098 1550);
FORCEPROP 2 LAST ROOM RISER1
J 0
(-3600 1600);
DISPLAY 0.829787 (-3600 1600);
PAINT RED (-3600 1600);
DISPLAY INVISIBLE (-3600 1600);
FORCEADD TAP..6
R 2
(-3100 1650);
FORCEPROP 3 LASTPIN (-3150 1650) SIG_NAME GMI_CPU0_G1_CPU1_G3_TX_DP<13>
J 0
(-3140 1660);
DISPLAY 0.659574 (-3140 1660);
PAINT MONO (-3140 1660);
DISPLAY INVISIBLE (-3140 1660);
FORCEPROP 1 LASTPIN (-3150 1650) BN 13
J 2
(-3098 1658);
DISPLAY 0.489362 (-3098 1658);
PAINT MONO (-3098 1658);
FORCEPROP 2 LAST CDS_LIB standard
J 0
(-3100 1650);
DISPLAY INVISIBLE (-3100 1650);
FORCEPROP 2 LAST BOM_COST IO_SLOT
J 0
(-3600 1750);
DISPLAY 0.829787 (-3600 1750);
DISPLAY INVISIBLE (-3600 1750);
FORCEPROP 1 LAST BODY_TYPE PLUMBING
J 2
(-3100 1600);
DISPLAY 0.702128 (-3100 1600);
PAINT GREEN (-3100 1600);
DISPLAY INVISIBLE (-3100 1600);
FORCEPROP 1 LAST HDL_TAP TRUE
J 2
(-3425 1525);
DISPLAY 0.702128 (-3425 1525);
PAINT GREEN (-3425 1525);
DISPLAY INVISIBLE (-3425 1525);
FORCEPROP 1 LAST PATH I340
J 2
(-3098 1650);
DISPLAY 0.872340 (-3098 1650);
PAINT GREEN (-3098 1650);
DISPLAY INVISIBLE (-3098 1650);
FORCEPROP 2 LAST ROOM RISER1
J 0
(-3600 1700);
DISPLAY 0.829787 (-3600 1700);
PAINT RED (-3600 1700);
DISPLAY INVISIBLE (-3600 1700);
FORCEADD TAP..6
R 2
(-3100 1750);
FORCEPROP 3 LASTPIN (-3150 1750) SIG_NAME GMI_CPU0_G1_CPU1_G3_TX_DP<12>
J 0
(-3140 1760);
DISPLAY 0.659574 (-3140 1760);
PAINT MONO (-3140 1760);
DISPLAY INVISIBLE (-3140 1760);
FORCEPROP 1 LASTPIN (-3150 1750) BN 12
J 2
(-3098 1758);
DISPLAY 0.489362 (-3098 1758);
PAINT MONO (-3098 1758);
FORCEPROP 2 LAST CDS_LIB standard
J 0
(-3100 1750);
DISPLAY INVISIBLE (-3100 1750);
FORCEPROP 2 LAST BOM_COST IO_SLOT
J 0
(-3600 1850);
DISPLAY 0.829787 (-3600 1850);
DISPLAY INVISIBLE (-3600 1850);
FORCEPROP 1 LAST BODY_TYPE PLUMBING
J 2
(-3100 1700);
DISPLAY 0.702128 (-3100 1700);
PAINT GREEN (-3100 1700);
DISPLAY INVISIBLE (-3100 1700);
FORCEPROP 1 LAST HDL_TAP TRUE
J 2
(-3425 1625);
DISPLAY 0.702128 (-3425 1625);
PAINT GREEN (-3425 1625);
DISPLAY INVISIBLE (-3425 1625);
FORCEPROP 1 LAST PATH I341
J 2
(-3098 1750);
DISPLAY 0.872340 (-3098 1750);
PAINT GREEN (-3098 1750);
DISPLAY INVISIBLE (-3098 1750);
FORCEPROP 2 LAST ROOM RISER1
J 0
(-3600 1800);
DISPLAY 0.829787 (-3600 1800);
PAINT RED (-3600 1800);
DISPLAY INVISIBLE (-3600 1800);
FORCEADD TAP..6
R 2
(-2950 1400);
FORCEPROP 3 LASTPIN (-3000 1400) SIG_NAME GMI_CPU0_G1_CPU1_G3_TX_DN<15>
J 0
(-2990 1410);
DISPLAY 0.659574 (-2990 1410);
PAINT MONO (-2990 1410);
DISPLAY INVISIBLE (-2990 1410);
FORCEPROP 1 LASTPIN (-3000 1400) BN 15
J 2
(-2948 1408);
DISPLAY 0.489362 (-2948 1408);
PAINT MONO (-2948 1408);
FORCEPROP 2 LAST BOM_COST IO_SLOT
J 0
(-3450 1500);
DISPLAY 0.829787 (-3450 1500);
DISPLAY INVISIBLE (-3450 1500);
FORCEPROP 2 LAST CDS_LIB standard
J 0
(-2950 1400);
DISPLAY INVISIBLE (-2950 1400);
FORCEPROP 1 LAST BODY_TYPE PLUMBING
J 2
(-2950 1350);
DISPLAY 0.702128 (-2950 1350);
PAINT GREEN (-2950 1350);
DISPLAY INVISIBLE (-2950 1350);
FORCEPROP 1 LAST HDL_TAP TRUE
J 2
(-3275 1275);
DISPLAY 0.702128 (-3275 1275);
PAINT GREEN (-3275 1275);
DISPLAY INVISIBLE (-3275 1275);
FORCEPROP 1 LAST PATH I342
J 2
(-2948 1400);
DISPLAY 0.872340 (-2948 1400);
PAINT GREEN (-2948 1400);
DISPLAY INVISIBLE (-2948 1400);
FORCEPROP 2 LAST ROOM RISER1
J 0
(-3450 1450);
DISPLAY 0.829787 (-3450 1450);
PAINT RED (-3450 1450);
DISPLAY INVISIBLE (-3450 1450);
FORCEADD TAP..6
R 2
(-2950 1500);
FORCEPROP 3 LASTPIN (-3000 1500) SIG_NAME GMI_CPU0_G1_CPU1_G3_TX_DN<14>
J 0
(-2990 1510);
DISPLAY 0.659574 (-2990 1510);
PAINT MONO (-2990 1510);
DISPLAY INVISIBLE (-2990 1510);
FORCEPROP 1 LASTPIN (-3000 1500) BN 14
J 2
(-2948 1508);
DISPLAY 0.489362 (-2948 1508);
PAINT MONO (-2948 1508);
FORCEPROP 2 LAST BOM_COST IO_SLOT
J 0
(-3450 1600);
DISPLAY 0.829787 (-3450 1600);
DISPLAY INVISIBLE (-3450 1600);
FORCEPROP 2 LAST CDS_LIB standard
J 0
(-2950 1500);
DISPLAY INVISIBLE (-2950 1500);
FORCEPROP 1 LAST BODY_TYPE PLUMBING
J 2
(-2950 1450);
DISPLAY 0.702128 (-2950 1450);
PAINT GREEN (-2950 1450);
DISPLAY INVISIBLE (-2950 1450);
FORCEPROP 1 LAST HDL_TAP TRUE
J 2
(-3275 1375);
DISPLAY 0.702128 (-3275 1375);
PAINT GREEN (-3275 1375);
DISPLAY INVISIBLE (-3275 1375);
FORCEPROP 1 LAST PATH I343
J 2
(-2948 1500);
DISPLAY 0.872340 (-2948 1500);
PAINT GREEN (-2948 1500);
DISPLAY INVISIBLE (-2948 1500);
FORCEPROP 2 LAST ROOM RISER1
J 0
(-3450 1550);
DISPLAY 0.829787 (-3450 1550);
PAINT RED (-3450 1550);
DISPLAY INVISIBLE (-3450 1550);
FORCEADD TAP..6
R 2
(-3100 1450);
FORCEPROP 3 LASTPIN (-3150 1450) SIG_NAME GMI_CPU0_G1_CPU1_G3_TX_DP<15>
J 0
(-3140 1460);
DISPLAY 0.659574 (-3140 1460);
PAINT MONO (-3140 1460);
DISPLAY INVISIBLE (-3140 1460);
FORCEPROP 1 LASTPIN (-3150 1450) BN 15
J 2
(-3098 1458);
DISPLAY 0.489362 (-3098 1458);
PAINT MONO (-3098 1458);
FORCEPROP 2 LAST CDS_LIB standard
J 0
(-3100 1450);
DISPLAY INVISIBLE (-3100 1450);
FORCEPROP 2 LAST BOM_COST IO_SLOT
J 0
(-3600 1550);
DISPLAY 0.829787 (-3600 1550);
DISPLAY INVISIBLE (-3600 1550);
FORCEPROP 1 LAST BODY_TYPE PLUMBING
J 2
(-3100 1400);
DISPLAY 0.702128 (-3100 1400);
PAINT GREEN (-3100 1400);
DISPLAY INVISIBLE (-3100 1400);
FORCEPROP 1 LAST HDL_TAP TRUE
J 2
(-3425 1325);
DISPLAY 0.702128 (-3425 1325);
PAINT GREEN (-3425 1325);
DISPLAY INVISIBLE (-3425 1325);
FORCEPROP 1 LAST PATH I344
J 2
(-3098 1450);
DISPLAY 0.872340 (-3098 1450);
PAINT GREEN (-3098 1450);
DISPLAY INVISIBLE (-3098 1450);
FORCEPROP 2 LAST ROOM RISER1
J 0
(-3600 1500);
DISPLAY 0.829787 (-3600 1500);
PAINT RED (-3600 1500);
DISPLAY INVISIBLE (-3600 1500);
FORCEADD TAP..6
(-6525 2950);
FORCEPROP 3 LASTPIN (-6475 2950) SIG_NAME GMI_CPU1_G3_CPU0_G1_TX_DP<0>
J 0
(-6465 2960);
DISPLAY 0.659574 (-6465 2960);
PAINT MONO (-6465 2960);
DISPLAY INVISIBLE (-6465 2960);
FORCEPROP 1 LASTPIN (-6475 2950) BN 0
J 0
(-6527 2958);
DISPLAY 0.489362 (-6527 2958);
PAINT MONO (-6527 2958);
FORCEPROP 2 LAST CDS_LIB mstr_standard
J 0
(-6525 2950);
DISPLAY INVISIBLE (-6525 2950);
FORCEPROP 1 LAST BODY_TYPE PLUMBING
J 0
(-6525 2900);
DISPLAY 0.574468 (-6525 2900);
PAINT GREEN (-6525 2900);
DISPLAY INVISIBLE (-6525 2900);
FORCEPROP 1 LAST HDL_TAP TRUE
J 0
(-6200 2825);
DISPLAY 0.574468 (-6200 2825);
PAINT GREEN (-6200 2825);
DISPLAY INVISIBLE (-6200 2825);
FORCEPROP 1 LAST PATH I345
J 0
(-6527 2950);
DISPLAY 0.872340 (-6527 2950);
PAINT GREEN (-6527 2950);
DISPLAY INVISIBLE (-6527 2950);
FORCEADD TAP..6
(-6525 2850);
FORCEPROP 3 LASTPIN (-6475 2850) SIG_NAME GMI_CPU1_G3_CPU0_G1_TX_DP<1>
J 0
(-6465 2860);
DISPLAY 0.659574 (-6465 2860);
PAINT MONO (-6465 2860);
DISPLAY INVISIBLE (-6465 2860);
FORCEPROP 1 LASTPIN (-6475 2850) BN 1
J 0
(-6527 2858);
DISPLAY 0.489362 (-6527 2858);
PAINT MONO (-6527 2858);
FORCEPROP 2 LAST CDS_LIB mstr_standard
J 0
(-6525 2850);
DISPLAY INVISIBLE (-6525 2850);
FORCEPROP 1 LAST BODY_TYPE PLUMBING
J 0
(-6525 2800);
DISPLAY 0.574468 (-6525 2800);
PAINT GREEN (-6525 2800);
DISPLAY INVISIBLE (-6525 2800);
FORCEPROP 1 LAST HDL_TAP TRUE
J 0
(-6200 2725);
DISPLAY 0.574468 (-6200 2725);
PAINT GREEN (-6200 2725);
DISPLAY INVISIBLE (-6200 2725);
FORCEPROP 1 LAST PATH I346
J 0
(-6527 2850);
DISPLAY 0.872340 (-6527 2850);
PAINT GREEN (-6527 2850);
DISPLAY INVISIBLE (-6527 2850);
FORCEADD TAP..6
(-6675 2900);
FORCEPROP 3 LASTPIN (-6625 2900) SIG_NAME GMI_CPU1_G3_CPU0_G1_TX_DN<0>
J 0
(-6615 2910);
DISPLAY 0.659574 (-6615 2910);
PAINT MONO (-6615 2910);
DISPLAY INVISIBLE (-6615 2910);
FORCEPROP 1 LASTPIN (-6625 2900) BN 0
J 0
(-6677 2908);
DISPLAY 0.489362 (-6677 2908);
PAINT MONO (-6677 2908);
FORCEPROP 2 LAST CDS_LIB mstr_standard
J 0
(-6675 2900);
DISPLAY INVISIBLE (-6675 2900);
FORCEPROP 1 LAST BODY_TYPE PLUMBING
J 0
(-6675 2850);
DISPLAY 0.574468 (-6675 2850);
PAINT GREEN (-6675 2850);
DISPLAY INVISIBLE (-6675 2850);
FORCEPROP 1 LAST HDL_TAP TRUE
J 0
(-6350 2775);
DISPLAY 0.574468 (-6350 2775);
PAINT GREEN (-6350 2775);
DISPLAY INVISIBLE (-6350 2775);
FORCEPROP 1 LAST PATH I347
J 0
(-6677 2900);
DISPLAY 0.872340 (-6677 2900);
PAINT GREEN (-6677 2900);
DISPLAY INVISIBLE (-6677 2900);
FORCEADD TAP..6
(-6525 2750);
FORCEPROP 3 LASTPIN (-6475 2750) SIG_NAME GMI_CPU1_G3_CPU0_G1_TX_DP<2>
J 0
(-6465 2760);
DISPLAY 0.659574 (-6465 2760);
PAINT MONO (-6465 2760);
DISPLAY INVISIBLE (-6465 2760);
FORCEPROP 1 LASTPIN (-6475 2750) BN 2
J 0
(-6527 2758);
DISPLAY 0.489362 (-6527 2758);
PAINT MONO (-6527 2758);
FORCEPROP 2 LAST CDS_LIB mstr_standard
J 0
(-6525 2750);
DISPLAY INVISIBLE (-6525 2750);
FORCEPROP 1 LAST BODY_TYPE PLUMBING
J 0
(-6525 2700);
DISPLAY 0.574468 (-6525 2700);
PAINT GREEN (-6525 2700);
DISPLAY INVISIBLE (-6525 2700);
FORCEPROP 1 LAST HDL_TAP TRUE
J 0
(-6200 2625);
DISPLAY 0.574468 (-6200 2625);
PAINT GREEN (-6200 2625);
DISPLAY INVISIBLE (-6200 2625);
FORCEPROP 1 LAST PATH I348
J 0
(-6527 2750);
DISPLAY 0.872340 (-6527 2750);
PAINT GREEN (-6527 2750);
DISPLAY INVISIBLE (-6527 2750);
FORCEADD TAP..6
(-6525 2650);
FORCEPROP 3 LASTPIN (-6475 2650) SIG_NAME GMI_CPU1_G3_CPU0_G1_TX_DP<3>
J 0
(-6465 2660);
DISPLAY 0.659574 (-6465 2660);
PAINT MONO (-6465 2660);
DISPLAY INVISIBLE (-6465 2660);
FORCEPROP 1 LASTPIN (-6475 2650) BN 3
J 0
(-6527 2658);
DISPLAY 0.489362 (-6527 2658);
PAINT MONO (-6527 2658);
FORCEPROP 2 LAST CDS_LIB standard
J 0
(-6525 2650);
DISPLAY INVISIBLE (-6525 2650);
FORCEPROP 1 LAST BODY_TYPE PLUMBING
J 0
(-6525 2600);
DISPLAY 0.574468 (-6525 2600);
PAINT GREEN (-6525 2600);
DISPLAY INVISIBLE (-6525 2600);
FORCEPROP 1 LAST HDL_TAP TRUE
J 0
(-6200 2525);
DISPLAY 0.574468 (-6200 2525);
PAINT GREEN (-6200 2525);
DISPLAY INVISIBLE (-6200 2525);
FORCEPROP 1 LAST PATH I349
J 0
(-6527 2650);
DISPLAY 0.872340 (-6527 2650);
PAINT GREEN (-6527 2650);
DISPLAY INVISIBLE (-6527 2650);
FORCEADD TAP..6
(-6675 2700);
FORCEPROP 3 LASTPIN (-6625 2700) SIG_NAME GMI_CPU1_G3_CPU0_G1_TX_DN<2>
J 0
(-6615 2710);
DISPLAY 0.659574 (-6615 2710);
PAINT MONO (-6615 2710);
DISPLAY INVISIBLE (-6615 2710);
FORCEPROP 1 LASTPIN (-6625 2700) BN 2
J 0
(-6677 2708);
DISPLAY 0.489362 (-6677 2708);
PAINT MONO (-6677 2708);
FORCEPROP 2 LAST CDS_LIB standard
J 0
(-6675 2700);
DISPLAY INVISIBLE (-6675 2700);
FORCEPROP 1 LAST BODY_TYPE PLUMBING
J 0
(-6675 2650);
DISPLAY 0.574468 (-6675 2650);
PAINT GREEN (-6675 2650);
DISPLAY INVISIBLE (-6675 2650);
FORCEPROP 1 LAST HDL_TAP TRUE
J 0
(-6350 2575);
DISPLAY 0.574468 (-6350 2575);
PAINT GREEN (-6350 2575);
DISPLAY INVISIBLE (-6350 2575);
FORCEPROP 1 LAST PATH I350
J 0
(-6677 2700);
DISPLAY 0.872340 (-6677 2700);
PAINT GREEN (-6677 2700);
DISPLAY INVISIBLE (-6677 2700);
FORCEADD TAP..6
(-6675 2800);
FORCEPROP 3 LASTPIN (-6625 2800) SIG_NAME GMI_CPU1_G3_CPU0_G1_TX_DN<1>
J 0
(-6615 2810);
DISPLAY 0.659574 (-6615 2810);
PAINT MONO (-6615 2810);
DISPLAY INVISIBLE (-6615 2810);
FORCEPROP 1 LASTPIN (-6625 2800) BN 1
J 0
(-6677 2808);
DISPLAY 0.489362 (-6677 2808);
PAINT MONO (-6677 2808);
FORCEPROP 2 LAST CDS_LIB mstr_standard
J 0
(-6675 2800);
DISPLAY INVISIBLE (-6675 2800);
FORCEPROP 1 LAST BODY_TYPE PLUMBING
J 0
(-6675 2750);
DISPLAY 0.574468 (-6675 2750);
PAINT GREEN (-6675 2750);
DISPLAY INVISIBLE (-6675 2750);
FORCEPROP 1 LAST HDL_TAP TRUE
J 0
(-6350 2675);
DISPLAY 0.574468 (-6350 2675);
PAINT GREEN (-6350 2675);
DISPLAY INVISIBLE (-6350 2675);
FORCEPROP 1 LAST PATH I351
J 0
(-6677 2800);
DISPLAY 0.872340 (-6677 2800);
PAINT GREEN (-6677 2800);
DISPLAY INVISIBLE (-6677 2800);
FORCEADD TAP..6
(-6675 2600);
FORCEPROP 3 LASTPIN (-6625 2600) SIG_NAME GMI_CPU1_G3_CPU0_G1_TX_DN<3>
J 0
(-6615 2610);
DISPLAY 0.659574 (-6615 2610);
PAINT MONO (-6615 2610);
DISPLAY INVISIBLE (-6615 2610);
FORCEPROP 1 LASTPIN (-6625 2600) BN 3
J 0
(-6677 2608);
DISPLAY 0.489362 (-6677 2608);
PAINT MONO (-6677 2608);
FORCEPROP 2 LAST CDS_LIB standard
J 0
(-6675 2600);
DISPLAY INVISIBLE (-6675 2600);
FORCEPROP 1 LAST BODY_TYPE PLUMBING
J 0
(-6675 2550);
DISPLAY 0.574468 (-6675 2550);
PAINT GREEN (-6675 2550);
DISPLAY INVISIBLE (-6675 2550);
FORCEPROP 1 LAST HDL_TAP TRUE
J 0
(-6350 2475);
DISPLAY 0.574468 (-6350 2475);
PAINT GREEN (-6350 2475);
DISPLAY INVISIBLE (-6350 2475);
FORCEPROP 1 LAST PATH I352
J 0
(-6677 2600);
DISPLAY 0.872340 (-6677 2600);
PAINT GREEN (-6677 2600);
DISPLAY INVISIBLE (-6677 2600);
FORCEADD TAP..6
(-6525 2550);
FORCEPROP 3 LASTPIN (-6475 2550) SIG_NAME GMI_CPU1_G3_CPU0_G1_TX_DP<4>
J 0
(-6465 2560);
DISPLAY 0.659574 (-6465 2560);
PAINT MONO (-6465 2560);
DISPLAY INVISIBLE (-6465 2560);
FORCEPROP 1 LASTPIN (-6475 2550) BN 4
J 0
(-6527 2558);
DISPLAY 0.489362 (-6527 2558);
PAINT MONO (-6527 2558);
FORCEPROP 2 LAST CDS_LIB standard
J 0
(-6525 2550);
DISPLAY INVISIBLE (-6525 2550);
FORCEPROP 1 LAST BODY_TYPE PLUMBING
J 0
(-6525 2500);
DISPLAY 0.574468 (-6525 2500);
PAINT GREEN (-6525 2500);
DISPLAY INVISIBLE (-6525 2500);
FORCEPROP 1 LAST HDL_TAP TRUE
J 0
(-6200 2425);
DISPLAY 0.574468 (-6200 2425);
PAINT GREEN (-6200 2425);
DISPLAY INVISIBLE (-6200 2425);
FORCEPROP 1 LAST PATH I353
J 0
(-6527 2550);
DISPLAY 0.872340 (-6527 2550);
PAINT GREEN (-6527 2550);
DISPLAY INVISIBLE (-6527 2550);
FORCEADD TAP..6
(-6525 2450);
FORCEPROP 3 LASTPIN (-6475 2450) SIG_NAME GMI_CPU1_G3_CPU0_G1_TX_DP<5>
J 0
(-6465 2460);
DISPLAY 0.659574 (-6465 2460);
PAINT MONO (-6465 2460);
DISPLAY INVISIBLE (-6465 2460);
FORCEPROP 1 LASTPIN (-6475 2450) BN 5
J 0
(-6527 2458);
DISPLAY 0.489362 (-6527 2458);
PAINT MONO (-6527 2458);
FORCEPROP 2 LAST CDS_LIB standard
J 0
(-6525 2450);
DISPLAY INVISIBLE (-6525 2450);
FORCEPROP 1 LAST BODY_TYPE PLUMBING
J 0
(-6525 2400);
DISPLAY 0.574468 (-6525 2400);
PAINT GREEN (-6525 2400);
DISPLAY INVISIBLE (-6525 2400);
FORCEPROP 1 LAST HDL_TAP TRUE
J 0
(-6200 2325);
DISPLAY 0.574468 (-6200 2325);
PAINT GREEN (-6200 2325);
DISPLAY INVISIBLE (-6200 2325);
FORCEPROP 1 LAST PATH I354
J 0
(-6527 2450);
DISPLAY 0.872340 (-6527 2450);
PAINT GREEN (-6527 2450);
DISPLAY INVISIBLE (-6527 2450);
FORCEADD TAP..6
(-6525 2350);
FORCEPROP 3 LASTPIN (-6475 2350) SIG_NAME GMI_CPU1_G3_CPU0_G1_TX_DP<6>
J 0
(-6465 2360);
DISPLAY 0.659574 (-6465 2360);
PAINT MONO (-6465 2360);
DISPLAY INVISIBLE (-6465 2360);
FORCEPROP 1 LASTPIN (-6475 2350) BN 6
J 0
(-6527 2358);
DISPLAY 0.489362 (-6527 2358);
PAINT MONO (-6527 2358);
FORCEPROP 2 LAST CDS_LIB standard
J 0
(-6525 2350);
DISPLAY INVISIBLE (-6525 2350);
FORCEPROP 1 LAST BODY_TYPE PLUMBING
J 0
(-6525 2300);
DISPLAY 0.574468 (-6525 2300);
PAINT GREEN (-6525 2300);
DISPLAY INVISIBLE (-6525 2300);
FORCEPROP 1 LAST HDL_TAP TRUE
J 0
(-6200 2225);
DISPLAY 0.574468 (-6200 2225);
PAINT GREEN (-6200 2225);
DISPLAY INVISIBLE (-6200 2225);
FORCEPROP 1 LAST PATH I355
J 0
(-6527 2350);
DISPLAY 0.872340 (-6527 2350);
PAINT GREEN (-6527 2350);
DISPLAY INVISIBLE (-6527 2350);
FORCEADD TAP..6
(-6675 2500);
FORCEPROP 3 LASTPIN (-6625 2500) SIG_NAME GMI_CPU1_G3_CPU0_G1_TX_DN<4>
J 0
(-6615 2510);
DISPLAY 0.659574 (-6615 2510);
PAINT MONO (-6615 2510);
DISPLAY INVISIBLE (-6615 2510);
FORCEPROP 1 LASTPIN (-6625 2500) BN 4
J 0
(-6677 2508);
DISPLAY 0.489362 (-6677 2508);
PAINT MONO (-6677 2508);
FORCEPROP 2 LAST CDS_LIB standard
J 0
(-6675 2500);
DISPLAY INVISIBLE (-6675 2500);
FORCEPROP 1 LAST BODY_TYPE PLUMBING
J 0
(-6675 2450);
DISPLAY 0.574468 (-6675 2450);
PAINT GREEN (-6675 2450);
DISPLAY INVISIBLE (-6675 2450);
FORCEPROP 1 LAST HDL_TAP TRUE
J 0
(-6350 2375);
DISPLAY 0.574468 (-6350 2375);
PAINT GREEN (-6350 2375);
DISPLAY INVISIBLE (-6350 2375);
FORCEPROP 1 LAST PATH I356
J 0
(-6677 2500);
DISPLAY 0.872340 (-6677 2500);
PAINT GREEN (-6677 2500);
DISPLAY INVISIBLE (-6677 2500);
FORCEADD TAP..6
(-6675 2400);
FORCEPROP 3 LASTPIN (-6625 2400) SIG_NAME GMI_CPU1_G3_CPU0_G1_TX_DN<5>
J 0
(-6615 2410);
DISPLAY 0.659574 (-6615 2410);
PAINT MONO (-6615 2410);
DISPLAY INVISIBLE (-6615 2410);
FORCEPROP 1 LASTPIN (-6625 2400) BN 5
J 0
(-6677 2408);
DISPLAY 0.489362 (-6677 2408);
PAINT MONO (-6677 2408);
FORCEPROP 2 LAST CDS_LIB standard
J 0
(-6675 2400);
DISPLAY INVISIBLE (-6675 2400);
FORCEPROP 1 LAST BODY_TYPE PLUMBING
J 0
(-6675 2350);
DISPLAY 0.574468 (-6675 2350);
PAINT GREEN (-6675 2350);
DISPLAY INVISIBLE (-6675 2350);
FORCEPROP 1 LAST HDL_TAP TRUE
J 0
(-6350 2275);
DISPLAY 0.574468 (-6350 2275);
PAINT GREEN (-6350 2275);
DISPLAY INVISIBLE (-6350 2275);
FORCEPROP 1 LAST PATH I357
J 0
(-6677 2400);
DISPLAY 0.872340 (-6677 2400);
PAINT GREEN (-6677 2400);
DISPLAY INVISIBLE (-6677 2400);
FORCEADD TAP..6
(-6525 2250);
FORCEPROP 3 LASTPIN (-6475 2250) SIG_NAME GMI_CPU1_G3_CPU0_G1_TX_DP<7>
J 0
(-6465 2260);
DISPLAY 0.659574 (-6465 2260);
PAINT MONO (-6465 2260);
DISPLAY INVISIBLE (-6465 2260);
FORCEPROP 1 LASTPIN (-6475 2250) BN 7
J 0
(-6527 2258);
DISPLAY 0.489362 (-6527 2258);
PAINT MONO (-6527 2258);
FORCEPROP 2 LAST CDS_LIB standard
J 0
(-6525 2250);
DISPLAY INVISIBLE (-6525 2250);
FORCEPROP 1 LAST BODY_TYPE PLUMBING
J 0
(-6525 2200);
DISPLAY 0.574468 (-6525 2200);
PAINT GREEN (-6525 2200);
DISPLAY INVISIBLE (-6525 2200);
FORCEPROP 1 LAST HDL_TAP TRUE
J 0
(-6200 2125);
DISPLAY 0.574468 (-6200 2125);
PAINT GREEN (-6200 2125);
DISPLAY INVISIBLE (-6200 2125);
FORCEPROP 1 LAST PATH I358
J 0
(-6527 2250);
DISPLAY 0.872340 (-6527 2250);
PAINT GREEN (-6527 2250);
DISPLAY INVISIBLE (-6527 2250);
FORCEADD TAP..6
(-6525 2150);
FORCEPROP 3 LASTPIN (-6475 2150) SIG_NAME GMI_CPU1_G3_CPU0_G1_TX_DP<8>
J 0
(-6465 2160);
DISPLAY 0.659574 (-6465 2160);
PAINT MONO (-6465 2160);
DISPLAY INVISIBLE (-6465 2160);
FORCEPROP 1 LASTPIN (-6475 2150) BN 8
J 0
(-6527 2158);
DISPLAY 0.489362 (-6527 2158);
PAINT MONO (-6527 2158);
FORCEPROP 2 LAST CDS_LIB standard
J 0
(-6525 2150);
DISPLAY INVISIBLE (-6525 2150);
FORCEPROP 1 LAST BODY_TYPE PLUMBING
J 0
(-6525 2100);
DISPLAY 0.574468 (-6525 2100);
PAINT GREEN (-6525 2100);
DISPLAY INVISIBLE (-6525 2100);
FORCEPROP 1 LAST HDL_TAP TRUE
J 0
(-6200 2025);
DISPLAY 0.574468 (-6200 2025);
PAINT GREEN (-6200 2025);
DISPLAY INVISIBLE (-6200 2025);
FORCEPROP 1 LAST PATH I359
J 0
(-6527 2150);
DISPLAY 0.872340 (-6527 2150);
PAINT GREEN (-6527 2150);
DISPLAY INVISIBLE (-6527 2150);
FORCEADD TAP..6
(-6525 2050);
FORCEPROP 3 LASTPIN (-6475 2050) SIG_NAME GMI_CPU1_G3_CPU0_G1_TX_DP<9>
J 0
(-6465 2060);
DISPLAY 0.659574 (-6465 2060);
PAINT MONO (-6465 2060);
DISPLAY INVISIBLE (-6465 2060);
FORCEPROP 1 LASTPIN (-6475 2050) BN 9
J 0
(-6527 2058);
DISPLAY 0.489362 (-6527 2058);
PAINT MONO (-6527 2058);
FORCEPROP 2 LAST CDS_LIB standard
J 0
(-6525 2050);
DISPLAY INVISIBLE (-6525 2050);
FORCEPROP 1 LAST BODY_TYPE PLUMBING
J 0
(-6525 2000);
DISPLAY 0.574468 (-6525 2000);
PAINT GREEN (-6525 2000);
DISPLAY INVISIBLE (-6525 2000);
FORCEPROP 1 LAST HDL_TAP TRUE
J 0
(-6200 1925);
DISPLAY 0.574468 (-6200 1925);
PAINT GREEN (-6200 1925);
DISPLAY INVISIBLE (-6200 1925);
FORCEPROP 1 LAST PATH I360
J 0
(-6527 2050);
DISPLAY 0.872340 (-6527 2050);
PAINT GREEN (-6527 2050);
DISPLAY INVISIBLE (-6527 2050);
FORCEADD TAP..6
(-6675 2200);
FORCEPROP 3 LASTPIN (-6625 2200) SIG_NAME GMI_CPU1_G3_CPU0_G1_TX_DN<7>
J 0
(-6615 2210);
DISPLAY 0.659574 (-6615 2210);
PAINT MONO (-6615 2210);
DISPLAY INVISIBLE (-6615 2210);
FORCEPROP 1 LASTPIN (-6625 2200) BN 7
J 0
(-6677 2208);
DISPLAY 0.489362 (-6677 2208);
PAINT MONO (-6677 2208);
FORCEPROP 2 LAST CDS_LIB standard
J 0
(-6675 2200);
DISPLAY INVISIBLE (-6675 2200);
FORCEPROP 1 LAST BODY_TYPE PLUMBING
J 0
(-6675 2150);
DISPLAY 0.574468 (-6675 2150);
PAINT GREEN (-6675 2150);
DISPLAY INVISIBLE (-6675 2150);
FORCEPROP 1 LAST HDL_TAP TRUE
J 0
(-6350 2075);
DISPLAY 0.574468 (-6350 2075);
PAINT GREEN (-6350 2075);
DISPLAY INVISIBLE (-6350 2075);
FORCEPROP 1 LAST PATH I361
J 0
(-6677 2200);
DISPLAY 0.872340 (-6677 2200);
PAINT GREEN (-6677 2200);
DISPLAY INVISIBLE (-6677 2200);
FORCEADD TAP..6
(-6675 2300);
FORCEPROP 3 LASTPIN (-6625 2300) SIG_NAME GMI_CPU1_G3_CPU0_G1_TX_DN<6>
J 0
(-6615 2310);
DISPLAY 0.659574 (-6615 2310);
PAINT MONO (-6615 2310);
DISPLAY INVISIBLE (-6615 2310);
FORCEPROP 1 LASTPIN (-6625 2300) BN 6
J 0
(-6677 2308);
DISPLAY 0.489362 (-6677 2308);
PAINT MONO (-6677 2308);
FORCEPROP 2 LAST CDS_LIB standard
J 0
(-6675 2300);
DISPLAY INVISIBLE (-6675 2300);
FORCEPROP 1 LAST BODY_TYPE PLUMBING
J 0
(-6675 2250);
DISPLAY 0.574468 (-6675 2250);
PAINT GREEN (-6675 2250);
DISPLAY INVISIBLE (-6675 2250);
FORCEPROP 1 LAST HDL_TAP TRUE
J 0
(-6350 2175);
DISPLAY 0.574468 (-6350 2175);
PAINT GREEN (-6350 2175);
DISPLAY INVISIBLE (-6350 2175);
FORCEPROP 1 LAST PATH I362
J 0
(-6677 2300);
DISPLAY 0.872340 (-6677 2300);
PAINT GREEN (-6677 2300);
DISPLAY INVISIBLE (-6677 2300);
FORCEADD TAP..6
(-6675 2100);
FORCEPROP 3 LASTPIN (-6625 2100) SIG_NAME GMI_CPU1_G3_CPU0_G1_TX_DN<8>
J 0
(-6615 2110);
DISPLAY 0.659574 (-6615 2110);
PAINT MONO (-6615 2110);
DISPLAY INVISIBLE (-6615 2110);
FORCEPROP 1 LASTPIN (-6625 2100) BN 8
J 0
(-6677 2108);
DISPLAY 0.489362 (-6677 2108);
PAINT MONO (-6677 2108);
FORCEPROP 2 LAST CDS_LIB standard
J 0
(-6675 2100);
DISPLAY INVISIBLE (-6675 2100);
FORCEPROP 1 LAST BODY_TYPE PLUMBING
J 0
(-6675 2050);
DISPLAY 0.574468 (-6675 2050);
PAINT GREEN (-6675 2050);
DISPLAY INVISIBLE (-6675 2050);
FORCEPROP 1 LAST HDL_TAP TRUE
J 0
(-6350 1975);
DISPLAY 0.574468 (-6350 1975);
PAINT GREEN (-6350 1975);
DISPLAY INVISIBLE (-6350 1975);
FORCEPROP 1 LAST PATH I363
J 0
(-6677 2100);
DISPLAY 0.872340 (-6677 2100);
PAINT GREEN (-6677 2100);
DISPLAY INVISIBLE (-6677 2100);
FORCEADD OFFPAGE..1
(-7625 3175);
FORCEPROP 2 LAST $XR0 50 
J 0
(-7846 3175);
DISPLAY 0.638298 (-7846 3175);
PAINT MONO (-7846 3175);
FORCEPROP 2 LAST CDS_LIB standard
J 0
(-7625 3175);
DISPLAY INVISIBLE (-7625 3175);
FORCEPROP 1 LAST OFFPAGE TRUE
J 0
(-7300 3050);
DISPLAY 0.872340 (-7300 3050);
PAINT GREEN (-7300 3050);
DISPLAY INVISIBLE (-7300 3050);
FORCEPROP 1 LAST COMMENT_BODY TRUE
J 0
(-7500 3075);
DISPLAY 0.872340 (-7500 3075);
PAINT GREEN (-7500 3075);
DISPLAY INVISIBLE (-7500 3075);
FORCEPROP 2 LAST PATH I364
J 0
(-7825 3225);
DISPLAY 1.021277 (-7825 3225);
DISPLAY INVISIBLE (-7825 3225);
FORCEADD OFFPAGE..1
(-7625 3125);
FORCEPROP 2 LASTPIN (-7575 3125) SIG_NAME GMI_CPU1_G3_CPU0_G1_TX_DN<15:0>
J 0
(-7585 3135);
DISPLAY 0.489362 (-7585 3135);
FORCEPROP 2 LAST $XR0 50 
J 0
(-7846 3125);
DISPLAY 0.638298 (-7846 3125);
PAINT MONO (-7846 3125);
FORCEPROP 2 LAST CDS_LIB standard
J 0
(-7625 3125);
DISPLAY INVISIBLE (-7625 3125);
FORCEPROP 1 LAST OFFPAGE TRUE
J 0
(-7300 3000);
DISPLAY 0.872340 (-7300 3000);
PAINT GREEN (-7300 3000);
DISPLAY INVISIBLE (-7300 3000);
FORCEPROP 1 LAST COMMENT_BODY TRUE
J 0
(-7500 3025);
DISPLAY 0.872340 (-7500 3025);
PAINT GREEN (-7500 3025);
DISPLAY INVISIBLE (-7500 3025);
FORCEPROP 2 LAST PATH I365
J 0
(-7825 3175);
DISPLAY 1.021277 (-7825 3175);
DISPLAY INVISIBLE (-7825 3175);
FORCEADD TAP..6
(-6525 1950);
FORCEPROP 3 LASTPIN (-6475 1950) SIG_NAME GMI_CPU1_G3_CPU0_G1_TX_DP<10>
J 0
(-6465 1960);
DISPLAY 0.659574 (-6465 1960);
PAINT MONO (-6465 1960);
DISPLAY INVISIBLE (-6465 1960);
FORCEPROP 1 LASTPIN (-6475 1950) BN 10
J 0
(-6527 1958);
DISPLAY 0.489362 (-6527 1958);
PAINT MONO (-6527 1958);
FORCEPROP 2 LAST CDS_LIB standard
J 0
(-6525 1950);
DISPLAY INVISIBLE (-6525 1950);
FORCEPROP 1 LAST BODY_TYPE PLUMBING
J 0
(-6525 1900);
DISPLAY 0.574468 (-6525 1900);
PAINT GREEN (-6525 1900);
DISPLAY INVISIBLE (-6525 1900);
FORCEPROP 1 LAST HDL_TAP TRUE
J 0
(-6200 1825);
DISPLAY 0.574468 (-6200 1825);
PAINT GREEN (-6200 1825);
DISPLAY INVISIBLE (-6200 1825);
FORCEPROP 1 LAST PATH I366
J 0
(-6527 1950);
DISPLAY 0.872340 (-6527 1950);
PAINT GREEN (-6527 1950);
DISPLAY INVISIBLE (-6527 1950);
FORCEADD TAP..6
(-6525 1850);
FORCEPROP 3 LASTPIN (-6475 1850) SIG_NAME GMI_CPU1_G3_CPU0_G1_TX_DP<11>
J 0
(-6465 1860);
DISPLAY 0.659574 (-6465 1860);
PAINT MONO (-6465 1860);
DISPLAY INVISIBLE (-6465 1860);
FORCEPROP 1 LASTPIN (-6475 1850) BN 11
J 0
(-6527 1858);
DISPLAY 0.489362 (-6527 1858);
PAINT MONO (-6527 1858);
FORCEPROP 2 LAST CDS_LIB standard
J 0
(-6525 1850);
DISPLAY INVISIBLE (-6525 1850);
FORCEPROP 1 LAST BODY_TYPE PLUMBING
J 0
(-6525 1800);
DISPLAY 0.574468 (-6525 1800);
PAINT GREEN (-6525 1800);
DISPLAY INVISIBLE (-6525 1800);
FORCEPROP 1 LAST HDL_TAP TRUE
J 0
(-6200 1725);
DISPLAY 0.574468 (-6200 1725);
PAINT GREEN (-6200 1725);
DISPLAY INVISIBLE (-6200 1725);
FORCEPROP 1 LAST PATH I367
J 0
(-6527 1850);
DISPLAY 0.872340 (-6527 1850);
PAINT GREEN (-6527 1850);
DISPLAY INVISIBLE (-6527 1850);
FORCEADD TAP..6
(-6675 2000);
FORCEPROP 3 LASTPIN (-6625 2000) SIG_NAME GMI_CPU1_G3_CPU0_G1_TX_DN<9>
J 0
(-6615 2010);
DISPLAY 0.659574 (-6615 2010);
PAINT MONO (-6615 2010);
DISPLAY INVISIBLE (-6615 2010);
FORCEPROP 1 LASTPIN (-6625 2000) BN 9
J 0
(-6677 2008);
DISPLAY 0.489362 (-6677 2008);
PAINT MONO (-6677 2008);
FORCEPROP 2 LAST CDS_LIB standard
J 0
(-6675 2000);
DISPLAY INVISIBLE (-6675 2000);
FORCEPROP 1 LAST BODY_TYPE PLUMBING
J 0
(-6675 1950);
DISPLAY 0.574468 (-6675 1950);
PAINT GREEN (-6675 1950);
DISPLAY INVISIBLE (-6675 1950);
FORCEPROP 1 LAST HDL_TAP TRUE
J 0
(-6350 1875);
DISPLAY 0.574468 (-6350 1875);
PAINT GREEN (-6350 1875);
DISPLAY INVISIBLE (-6350 1875);
FORCEPROP 1 LAST PATH I368
J 0
(-6677 2000);
DISPLAY 0.872340 (-6677 2000);
PAINT GREEN (-6677 2000);
DISPLAY INVISIBLE (-6677 2000);
FORCEADD TAP..6
(-6675 1900);
FORCEPROP 3 LASTPIN (-6625 1900) SIG_NAME GMI_CPU1_G3_CPU0_G1_TX_DN<10>
J 0
(-6615 1910);
DISPLAY 0.659574 (-6615 1910);
PAINT MONO (-6615 1910);
DISPLAY INVISIBLE (-6615 1910);
FORCEPROP 1 LASTPIN (-6625 1900) BN 10
J 0
(-6677 1908);
DISPLAY 0.489362 (-6677 1908);
PAINT MONO (-6677 1908);
FORCEPROP 2 LAST CDS_LIB standard
J 0
(-6675 1900);
DISPLAY INVISIBLE (-6675 1900);
FORCEPROP 1 LAST BODY_TYPE PLUMBING
J 0
(-6675 1850);
DISPLAY 0.574468 (-6675 1850);
PAINT GREEN (-6675 1850);
DISPLAY INVISIBLE (-6675 1850);
FORCEPROP 1 LAST HDL_TAP TRUE
J 0
(-6350 1775);
DISPLAY 0.574468 (-6350 1775);
PAINT GREEN (-6350 1775);
DISPLAY INVISIBLE (-6350 1775);
FORCEPROP 1 LAST PATH I369
J 0
(-6677 1900);
DISPLAY 0.872340 (-6677 1900);
PAINT GREEN (-6677 1900);
DISPLAY INVISIBLE (-6677 1900);
FORCEADD TAP..6
(-6675 1800);
FORCEPROP 3 LASTPIN (-6625 1800) SIG_NAME GMI_CPU1_G3_CPU0_G1_TX_DN<11>
J 0
(-6615 1810);
DISPLAY 0.659574 (-6615 1810);
PAINT MONO (-6615 1810);
DISPLAY INVISIBLE (-6615 1810);
FORCEPROP 1 LASTPIN (-6625 1800) BN 11
J 0
(-6677 1808);
DISPLAY 0.489362 (-6677 1808);
PAINT MONO (-6677 1808);
FORCEPROP 2 LAST CDS_LIB standard
J 0
(-6675 1800);
DISPLAY INVISIBLE (-6675 1800);
FORCEPROP 1 LAST BODY_TYPE PLUMBING
J 0
(-6675 1750);
DISPLAY 0.574468 (-6675 1750);
PAINT GREEN (-6675 1750);
DISPLAY INVISIBLE (-6675 1750);
FORCEPROP 1 LAST HDL_TAP TRUE
J 0
(-6350 1675);
DISPLAY 0.574468 (-6350 1675);
PAINT GREEN (-6350 1675);
DISPLAY INVISIBLE (-6350 1675);
FORCEPROP 1 LAST PATH I370
J 0
(-6677 1800);
DISPLAY 0.872340 (-6677 1800);
PAINT GREEN (-6677 1800);
DISPLAY INVISIBLE (-6677 1800);
FORCEADD TAP..6
(-6525 1750);
FORCEPROP 3 LASTPIN (-6475 1750) SIG_NAME GMI_CPU1_G3_CPU0_G1_TX_DP<12>
J 0
(-6465 1760);
DISPLAY 0.659574 (-6465 1760);
PAINT MONO (-6465 1760);
DISPLAY INVISIBLE (-6465 1760);
FORCEPROP 1 LASTPIN (-6475 1750) BN 12
J 0
(-6527 1758);
DISPLAY 0.489362 (-6527 1758);
PAINT MONO (-6527 1758);
FORCEPROP 2 LAST CDS_LIB standard
J 0
(-6525 1750);
DISPLAY INVISIBLE (-6525 1750);
FORCEPROP 1 LAST BODY_TYPE PLUMBING
J 0
(-6525 1700);
DISPLAY 0.574468 (-6525 1700);
PAINT GREEN (-6525 1700);
DISPLAY INVISIBLE (-6525 1700);
FORCEPROP 1 LAST HDL_TAP TRUE
J 0
(-6200 1625);
DISPLAY 0.574468 (-6200 1625);
PAINT GREEN (-6200 1625);
DISPLAY INVISIBLE (-6200 1625);
FORCEPROP 1 LAST PATH I371
J 0
(-6527 1750);
DISPLAY 0.872340 (-6527 1750);
PAINT GREEN (-6527 1750);
DISPLAY INVISIBLE (-6527 1750);
FORCEADD TAP..6
(-6525 1650);
FORCEPROP 3 LASTPIN (-6475 1650) SIG_NAME GMI_CPU1_G3_CPU0_G1_TX_DP<13>
J 0
(-6465 1660);
DISPLAY 0.659574 (-6465 1660);
PAINT MONO (-6465 1660);
DISPLAY INVISIBLE (-6465 1660);
FORCEPROP 1 LASTPIN (-6475 1650) BN 13
J 0
(-6527 1658);
DISPLAY 0.489362 (-6527 1658);
PAINT MONO (-6527 1658);
FORCEPROP 2 LAST CDS_LIB standard
J 0
(-6525 1650);
DISPLAY INVISIBLE (-6525 1650);
FORCEPROP 1 LAST BODY_TYPE PLUMBING
J 0
(-6525 1600);
DISPLAY 0.574468 (-6525 1600);
PAINT GREEN (-6525 1600);
DISPLAY INVISIBLE (-6525 1600);
FORCEPROP 1 LAST HDL_TAP TRUE
J 0
(-6200 1525);
DISPLAY 0.574468 (-6200 1525);
PAINT GREEN (-6200 1525);
DISPLAY INVISIBLE (-6200 1525);
FORCEPROP 1 LAST PATH I372
J 0
(-6527 1650);
DISPLAY 0.872340 (-6527 1650);
PAINT GREEN (-6527 1650);
DISPLAY INVISIBLE (-6527 1650);
FORCEADD TAP..6
(-6525 1550);
FORCEPROP 3 LASTPIN (-6475 1550) SIG_NAME GMI_CPU1_G3_CPU0_G1_TX_DP<14>
J 0
(-6465 1560);
DISPLAY 0.659574 (-6465 1560);
PAINT MONO (-6465 1560);
DISPLAY INVISIBLE (-6465 1560);
FORCEPROP 1 LASTPIN (-6475 1550) BN 14
J 0
(-6527 1558);
DISPLAY 0.489362 (-6527 1558);
PAINT MONO (-6527 1558);
FORCEPROP 2 LAST CDS_LIB standard
J 0
(-6525 1550);
DISPLAY INVISIBLE (-6525 1550);
FORCEPROP 1 LAST BODY_TYPE PLUMBING
J 0
(-6525 1500);
DISPLAY 0.574468 (-6525 1500);
PAINT GREEN (-6525 1500);
DISPLAY INVISIBLE (-6525 1500);
FORCEPROP 1 LAST HDL_TAP TRUE
J 0
(-6200 1425);
DISPLAY 0.574468 (-6200 1425);
PAINT GREEN (-6200 1425);
DISPLAY INVISIBLE (-6200 1425);
FORCEPROP 1 LAST PATH I373
J 0
(-6527 1550);
DISPLAY 0.872340 (-6527 1550);
PAINT GREEN (-6527 1550);
DISPLAY INVISIBLE (-6527 1550);
FORCEADD TAP..6
(-6675 1700);
FORCEPROP 3 LASTPIN (-6625 1700) SIG_NAME GMI_CPU1_G3_CPU0_G1_TX_DN<12>
J 0
(-6615 1710);
DISPLAY 0.659574 (-6615 1710);
PAINT MONO (-6615 1710);
DISPLAY INVISIBLE (-6615 1710);
FORCEPROP 1 LASTPIN (-6625 1700) BN 12
J 0
(-6677 1708);
DISPLAY 0.489362 (-6677 1708);
PAINT MONO (-6677 1708);
FORCEPROP 2 LAST CDS_LIB standard
J 0
(-6675 1700);
DISPLAY INVISIBLE (-6675 1700);
FORCEPROP 1 LAST BODY_TYPE PLUMBING
J 0
(-6675 1650);
DISPLAY 0.574468 (-6675 1650);
PAINT GREEN (-6675 1650);
DISPLAY INVISIBLE (-6675 1650);
FORCEPROP 1 LAST HDL_TAP TRUE
J 0
(-6350 1575);
DISPLAY 0.574468 (-6350 1575);
PAINT GREEN (-6350 1575);
DISPLAY INVISIBLE (-6350 1575);
FORCEPROP 1 LAST PATH I374
J 0
(-6677 1700);
DISPLAY 0.872340 (-6677 1700);
PAINT GREEN (-6677 1700);
DISPLAY INVISIBLE (-6677 1700);
FORCEADD TAP..6
(-6675 1600);
FORCEPROP 3 LASTPIN (-6625 1600) SIG_NAME GMI_CPU1_G3_CPU0_G1_TX_DN<13>
J 0
(-6615 1610);
DISPLAY 0.659574 (-6615 1610);
PAINT MONO (-6615 1610);
DISPLAY INVISIBLE (-6615 1610);
FORCEPROP 1 LASTPIN (-6625 1600) BN 13
J 0
(-6677 1608);
DISPLAY 0.489362 (-6677 1608);
PAINT MONO (-6677 1608);
FORCEPROP 2 LAST CDS_LIB standard
J 0
(-6675 1600);
DISPLAY INVISIBLE (-6675 1600);
FORCEPROP 1 LAST BODY_TYPE PLUMBING
J 0
(-6675 1550);
DISPLAY 0.574468 (-6675 1550);
PAINT GREEN (-6675 1550);
DISPLAY INVISIBLE (-6675 1550);
FORCEPROP 1 LAST HDL_TAP TRUE
J 0
(-6350 1475);
DISPLAY 0.574468 (-6350 1475);
PAINT GREEN (-6350 1475);
DISPLAY INVISIBLE (-6350 1475);
FORCEPROP 1 LAST PATH I375
J 0
(-6677 1600);
DISPLAY 0.872340 (-6677 1600);
PAINT GREEN (-6677 1600);
DISPLAY INVISIBLE (-6677 1600);
FORCEADD TAP..6
(-6525 1450);
FORCEPROP 3 LASTPIN (-6475 1450) SIG_NAME GMI_CPU1_G3_CPU0_G1_TX_DP<15>
J 0
(-6465 1460);
DISPLAY 0.659574 (-6465 1460);
PAINT MONO (-6465 1460);
DISPLAY INVISIBLE (-6465 1460);
FORCEPROP 1 LASTPIN (-6475 1450) BN 15
J 0
(-6527 1458);
DISPLAY 0.489362 (-6527 1458);
PAINT MONO (-6527 1458);
FORCEPROP 2 LAST CDS_LIB standard
J 0
(-6525 1450);
DISPLAY INVISIBLE (-6525 1450);
FORCEPROP 1 LAST BODY_TYPE PLUMBING
J 0
(-6525 1400);
DISPLAY 0.574468 (-6525 1400);
PAINT GREEN (-6525 1400);
DISPLAY INVISIBLE (-6525 1400);
FORCEPROP 1 LAST HDL_TAP TRUE
J 0
(-6200 1325);
DISPLAY 0.574468 (-6200 1325);
PAINT GREEN (-6200 1325);
DISPLAY INVISIBLE (-6200 1325);
FORCEPROP 1 LAST PATH I376
J 0
(-6527 1450);
DISPLAY 0.872340 (-6527 1450);
PAINT GREEN (-6527 1450);
DISPLAY INVISIBLE (-6527 1450);
FORCEADD TAP..6
(-6675 1400);
FORCEPROP 3 LASTPIN (-6625 1400) SIG_NAME GMI_CPU1_G3_CPU0_G1_TX_DN<15>
J 0
(-6615 1410);
DISPLAY 0.659574 (-6615 1410);
PAINT MONO (-6615 1410);
DISPLAY INVISIBLE (-6615 1410);
FORCEPROP 1 LASTPIN (-6625 1400) BN 15
J 0
(-6677 1408);
DISPLAY 0.489362 (-6677 1408);
PAINT MONO (-6677 1408);
FORCEPROP 2 LAST CDS_LIB standard
J 0
(-6675 1400);
DISPLAY INVISIBLE (-6675 1400);
FORCEPROP 1 LAST BODY_TYPE PLUMBING
J 0
(-6675 1350);
DISPLAY 0.574468 (-6675 1350);
PAINT GREEN (-6675 1350);
DISPLAY INVISIBLE (-6675 1350);
FORCEPROP 1 LAST HDL_TAP TRUE
J 0
(-6350 1275);
DISPLAY 0.574468 (-6350 1275);
PAINT GREEN (-6350 1275);
DISPLAY INVISIBLE (-6350 1275);
FORCEPROP 1 LAST PATH I377
J 0
(-6677 1400);
DISPLAY 0.872340 (-6677 1400);
PAINT GREEN (-6677 1400);
DISPLAY INVISIBLE (-6677 1400);
FORCEADD TAP..6
(-6675 1500);
FORCEPROP 3 LASTPIN (-6625 1500) SIG_NAME GMI_CPU1_G3_CPU0_G1_TX_DN<14>
J 0
(-6615 1510);
DISPLAY 0.659574 (-6615 1510);
PAINT MONO (-6615 1510);
DISPLAY INVISIBLE (-6615 1510);
FORCEPROP 1 LASTPIN (-6625 1500) BN 14
J 0
(-6677 1508);
DISPLAY 0.489362 (-6677 1508);
PAINT MONO (-6677 1508);
FORCEPROP 2 LAST CDS_LIB standard
J 0
(-6675 1500);
DISPLAY INVISIBLE (-6675 1500);
FORCEPROP 1 LAST BODY_TYPE PLUMBING
J 0
(-6675 1450);
DISPLAY 0.574468 (-6675 1450);
PAINT GREEN (-6675 1450);
DISPLAY INVISIBLE (-6675 1450);
FORCEPROP 1 LAST HDL_TAP TRUE
J 0
(-6350 1375);
DISPLAY 0.574468 (-6350 1375);
PAINT GREEN (-6350 1375);
DISPLAY INVISIBLE (-6350 1375);
FORCEPROP 1 LAST PATH I378
J 0
(-6677 1500);
DISPLAY 0.872340 (-6677 1500);
PAINT GREEN (-6677 1500);
DISPLAY INVISIBLE (-6677 1500);
FORCEADD QUANTA_TITLE_BLOCK_C..1
(-100 100);
FORCEPROP 0 LAST CDS_CON_LAST_MODIFIED Fri Mar 11 14:52:18 2022
J 0
(-1985 115);
DISPLAY INVISIBLE (-1985 115);
FORCEPROP 1 LAST CUSTOM_TXT_CDS <CON_LAST_MODIFIED>
J 0
(-1985 115);
DISPLAY 0.978723 (-1985 115);
FORCEPROP 2 LAST CUSTOM_TXT_CDS <XR_PAGE_TITLE>
J 0
(-7990 5350);
DISPLAY 0.638298 (-7990 5350);
PAINT PINK (-7990 5350);
DISPLAY INVISIBLE (-7990 5350);
FORCEPROP 1 LAST CUSTOM_TXT_CDS <NAME_2>
J 0
(-3275 150);
FORCEPROP 1 LAST CUSTOM_TXT_CDS <NAME_1>
J 0
(-3275 275);
FORCEPROP 1 LAST CUSTOM_TXT_CDS <Q_NUMBER>
J 0
(-1503 203);
DISPLAY 1.212766 (-1503 203);
FORCEPROP 1 LAST CUSTOM_TXT_CDS <Q_PROJ>
J 0
(-2482 202);
DISPLAY 1.212766 (-2482 202);
FORCEPROP 1 LAST CUSTOM_TXT_CDS <Q_REV>
J 0
(-284 203);
DISPLAY 1.212766 (-284 203);
FORCEPROP 1 LAST CUSTOM_TXT_CDS <CON_PAGE_NUM> OF <CON_TOTAL_PAGES>
J 0
(-546 118);
DISPLAY 0.978723 (-546 118);
FORCEPROP 1 LAST Q_DEPT BU9
J 1
(-3863 149);
DISPLAY 1.957447 (-3863 149);
PAINT GREEN (-3863 149);
FORCEPROP 1 LAST Q_TITLE CPU0 PCIE G0/G1
J 0
(-9375 150);
DISPLAY 2.446809 (-9375 150);
PAINT GREEN (-9375 150);
FORCEPROP 2 LAST PAGE_BORDER TRUE
J 0
(-7990 5350);
DISPLAY 0.638298 (-7990 5350);
PAINT PINK (-7990 5350);
DISPLAY INVISIBLE (-7990 5350);
FORCEPROP 1 LAST CDS_LMAN_SYM_OUTLINE -9475,6775,100,-125
J 0
(-100 100);
DISPLAY 0.468085 (-100 100);
PAINT GREEN (-100 100);
DISPLAY INVISIBLE (-100 100);
FORCEPROP 2 LAST CDS_LIB pure_quanta
J 0
(-100 100);
DISPLAY INVISIBLE (-100 100);
FORCEPROP 1 LAST COMMENT_BODY TRUE
J 0
(-88 87);
DISPLAY 0.978723 (-88 87);
PAINT GREEN (-88 87);
DISPLAY INVISIBLE (-88 87);
FORCEPROP 2 LAST CDS_XR_PAGE_TITLE CR-22 : @T6G_MB_LIB.T6G(SCH_1):PAGE22
J 0
(-7990 5350);
DISPLAY 0.638298 (-7990 5350);
PAINT PINK (-7990 5350);
DISPLAY INVISIBLE (-7990 5350);
WIRE 17 -1 (-2900 5650)(-2900 5550);
WIRE 17 -1 (-2900 5850)(-2900 5650);
WIRE 17 -1 (-2900 5550)(-2900 5450);
WIRE 17 -1 (-2900 5450)(-2900 5350);
WIRE 17 -1 (-2900 5850)(-1875 5850);
FORCEPROP 2 LAST SIG_NAME GMI_CPU0_G0_CPU1_G2_TX_DN<15:0>
J 0
(-2860 5860);
DISPLAY 0.489362 (-2860 5860);
WIRE 17 -1 (-2900 5350)(-2900 5250);
WIRE 17 -1 (-2900 5250)(-2900 5150);
WIRE 17 -1 (-2900 5150)(-2900 5050);
WIRE 17 -1 (-2900 5050)(-2900 4950);
WIRE 17 -1 (-2900 4950)(-2900 4850);
WIRE 17 -1 (-2900 4850)(-2900 4750);
WIRE 17 -1 (-2900 4750)(-2900 4650);
WIRE 17 -1 (-2900 4650)(-2900 4550);
WIRE 17 -1 (-2900 4550)(-2900 4450);
WIRE 17 -1 (-2900 4450)(-2900 4350);
WIRE 17 -1 (-2900 4350)(-2900 4250);
WIRE 17 -1 (-2900 4250)(-2900 4150);
WIRE 17 -1 (-3050 5700)(-3050 5600);
WIRE 17 -1 (-3050 5900)(-3050 5700);
WIRE 17 -1 (-3050 5600)(-3050 5500);
WIRE 17 -1 (-3050 5500)(-3050 5400);
WIRE 17 -1 (-3050 5900)(-1875 5900);
FORCEPROP 2 LAST SIG_NAME GMI_CPU0_G0_CPU1_G2_TX_DP<15:0>
J 0
(-2860 5910);
DISPLAY 0.489362 (-2860 5910);
WIRE 17 -1 (-3050 5400)(-3050 5300);
WIRE 17 -1 (-3050 5300)(-3050 5200);
WIRE 17 -1 (-3050 5200)(-3050 5100);
WIRE 17 -1 (-3050 5100)(-3050 5000);
WIRE 17 -1 (-3050 5000)(-3050 4900);
WIRE 17 -1 (-3050 4900)(-3050 4800);
WIRE 17 -1 (-3050 4800)(-3050 4700);
WIRE 17 -1 (-3050 4700)(-3050 4600);
WIRE 17 -1 (-3050 4600)(-3050 4500);
WIRE 17 -1 (-3050 4500)(-3050 4400);
WIRE 17 -1 (-3050 4400)(-3050 4300);
WIRE 17 -1 (-3050 4300)(-3050 4200);
WIRE 17 -1 (-2900 2125)(-2900 2025);
WIRE 17 -1 (-2900 2225)(-2900 2125);
WIRE 17 -1 (-2900 2025)(-2900 1925);
WIRE 17 -1 (-2900 1925)(-2900 1825);
WIRE 17 -1 (-2900 2325)(-2900 2225);
WIRE 17 -1 (-2900 2425)(-2900 2325);
WIRE 17 -1 (-2900 1825)(-2900 1725);
WIRE 17 -1 (-2900 1725)(-2900 1625);
WIRE 17 -1 (-2900 2525)(-2900 2425);
WIRE 17 -1 (-2900 2625)(-2900 2525);
WIRE 17 -1 (-2900 1625)(-2900 1525);
WIRE 17 -1 (-2900 1525)(-2900 1425);
WIRE 17 -1 (-2900 2725)(-2900 2625);
WIRE 17 -1 (-2900 2825)(-2900 2725);
WIRE 17 -1 (-2900 2925)(-2900 2825);
WIRE 17 -1 (-2900 3125)(-2900 2925);
WIRE 17 -1 (-2900 3125)(-2025 3125);
FORCEPROP 2 LAST SIG_NAME GMI_CPU0_G1_CPU1_G3_TX_DN<15:0>
J 0
(-2935 3135);
DISPLAY 0.489362 (-2935 3135);
WIRE 17 -1 (-3050 2975)(-3050 2875);
WIRE 17 -1 (-3050 3175)(-3050 2975);
WIRE 17 -1 (-3050 2875)(-3050 2775);
WIRE 17 -1 (-3050 2775)(-3050 2675);
WIRE 17 -1 (-3050 3175)(-2025 3175);
FORCEPROP 2 LAST SIG_NAME GMI_CPU0_G1_CPU1_G3_TX_DP<15:0>
J 0
(-2935 3185);
DISPLAY 0.489362 (-2935 3185);
WIRE 17 -1 (-3050 2675)(-3050 2575);
WIRE 17 -1 (-3050 2575)(-3050 2475);
WIRE 17 -1 (-3050 2475)(-3050 2375);
WIRE 17 -1 (-3050 2375)(-3050 2275);
WIRE 17 -1 (-3050 2275)(-3050 2175);
WIRE 17 -1 (-3050 2075)(-3050 1975);
WIRE 17 -1 (-3050 2175)(-3050 2075);
WIRE 17 -1 (-3050 1975)(-3050 1875);
WIRE 17 -1 (-3050 1875)(-3050 1775);
WIRE 17 -1 (-3050 1775)(-3050 1675);
WIRE 17 -1 (-3050 1675)(-3050 1575);
WIRE 17 -1 (-3050 1575)(-3050 1475);
WIRE 17 -1 (-6725 5650)(-6725 5850);
WIRE 17 -1 (-6725 5550)(-6725 5650);
WIRE 17 -1 (-6725 5850)(-7725 5850);
FORCEPROP 2 LAST SIG_NAME GMI_CPU1_G2_CPU0_G0_TX_DN<15:0>
J 0
(-7685 5860);
DISPLAY 0.489362 (-7685 5860);
WIRE 17 -1 (-6725 5450)(-6725 5550);
WIRE 17 -1 (-6725 5350)(-6725 5450);
WIRE 17 -1 (-6725 5250)(-6725 5350);
WIRE 17 -1 (-6725 5150)(-6725 5250);
WIRE 17 -1 (-6725 5050)(-6725 5150);
WIRE 17 -1 (-6725 4950)(-6725 5050);
WIRE 17 -1 (-6725 4850)(-6725 4950);
WIRE 17 -1 (-6725 4750)(-6725 4850);
WIRE 17 -1 (-6725 4650)(-6725 4750);
WIRE 17 -1 (-6725 4550)(-6725 4650);
WIRE 17 -1 (-6725 4450)(-6725 4550);
WIRE 17 -1 (-6725 4350)(-6725 4450);
WIRE 17 -1 (-6725 4250)(-6725 4350);
WIRE 17 -1 (-6725 4150)(-6725 4250);
WIRE 17 -1 (-6575 5700)(-6575 5900);
WIRE 17 -1 (-6575 5600)(-6575 5700);
WIRE 17 -1 (-6575 5900)(-7725 5900);
FORCEPROP 2 LAST SIG_NAME GMI_CPU1_G2_CPU0_G0_TX_DP<15:0>
J 0
(-7685 5910);
DISPLAY 0.489362 (-7685 5910);
WIRE 17 -1 (-6575 5500)(-6575 5600);
WIRE 17 -1 (-6575 5400)(-6575 5500);
WIRE 17 -1 (-6575 5300)(-6575 5400);
WIRE 17 -1 (-6575 5200)(-6575 5300);
WIRE 17 -1 (-6575 5100)(-6575 5200);
WIRE 17 -1 (-6575 5000)(-6575 5100);
WIRE 17 -1 (-6575 4900)(-6575 5000);
WIRE 17 -1 (-6575 4800)(-6575 4900);
WIRE 17 -1 (-6575 4700)(-6575 4800);
WIRE 17 -1 (-6575 4600)(-6575 4700);
WIRE 17 -1 (-6575 4500)(-6575 4600);
WIRE 17 -1 (-6575 4400)(-6575 4500);
WIRE 17 -1 (-6575 4300)(-6575 4400);
WIRE 17 -1 (-6575 4200)(-6575 4300);
WIRE 17 -1 (-6575 1475)(-6575 1575);
WIRE 17 -1 (-6575 1575)(-6575 1675);
WIRE 17 -1 (-6575 1675)(-6575 1775);
WIRE 17 -1 (-6575 1775)(-6575 1875);
WIRE 17 -1 (-6575 1875)(-6575 1975);
WIRE 17 -1 (-6575 1975)(-6575 2075);
WIRE 17 -1 (-6575 2075)(-6575 2175);
WIRE 17 -1 (-6575 2175)(-6575 2275);
WIRE 17 -1 (-6575 2275)(-6575 2375);
WIRE 17 -1 (-6575 2375)(-6575 2475);
WIRE 17 -1 (-6575 2475)(-6575 2575);
WIRE 17 -1 (-6575 2575)(-6575 2675);
WIRE 17 -1 (-6575 2675)(-6575 2775);
WIRE 17 -1 (-6575 2775)(-6575 2875);
WIRE 17 -1 (-6575 2875)(-6575 2975);
WIRE 17 -1 (-6575 2975)(-6575 3175);
WIRE 17 -1 (-6575 3175)(-7575 3175);
FORCEPROP 2 LAST SIG_NAME GMI_CPU1_G3_CPU0_G1_TX_DP<15:0>
J 0
(-7585 3185);
DISPLAY 0.489362 (-7585 3185);
WIRE 17 -1 (-6725 1425)(-6725 1525);
WIRE 17 -1 (-6725 1525)(-6725 1625);
WIRE 17 -1 (-6725 1625)(-6725 1725);
WIRE 17 -1 (-6725 1725)(-6725 1825);
WIRE 17 -1 (-6725 1825)(-6725 1925);
WIRE 17 -1 (-6725 1925)(-6725 2025);
WIRE 17 -1 (-6725 2025)(-6725 2125);
WIRE 17 -1 (-6725 2125)(-6725 2225);
WIRE 17 -1 (-6725 2225)(-6725 2325);
WIRE 17 -1 (-6725 2325)(-6725 2425);
WIRE 17 -1 (-6725 2425)(-6725 2525);
WIRE 17 -1 (-6725 2525)(-6725 2625);
WIRE 17 -1 (-6725 2625)(-6725 2725);
WIRE 17 -1 (-6725 2725)(-6725 2825);
WIRE 17 -1 (-6725 2825)(-6725 2925);
WIRE 17 -1 (-6725 2925)(-6725 3125);
WIRE 17 -1 (-6725 3125)(-7575 3125);
WIRE 16 -1 (-6475 4975)(-6025 4975);
WIRE 16 -1 (-6625 2200)(-6025 2200);
WIRE 16 -1 (-6625 2300)(-6025 2300);
WIRE 16 -1 (-6625 2400)(-6025 2400);
WIRE 16 -1 (-6475 2250)(-6025 2250);
WIRE 16 -1 (-6625 2500)(-6025 2500);
WIRE 16 -1 (-6475 2350)(-6025 2350);
WIRE 16 -1 (-6625 2600)(-6025 2600);
WIRE 16 -1 (-6475 2450)(-6025 2450);
WIRE 16 -1 (-6625 2700)(-6025 2700);
WIRE 16 -1 (-6475 2550)(-6025 2550);
WIRE 16 -1 (-6625 2800)(-6025 2800);
WIRE 16 -1 (-6475 2650)(-6025 2650);
WIRE 16 -1 (-6625 2900)(-6025 2900);
WIRE 16 -1 (-6475 2750)(-6025 2750);
WIRE 16 -1 (-6475 2850)(-6025 2850);
WIRE 16 -1 (-6475 2950)(-6025 2950);
WIRE 16 -1 (-6625 2100)(-6025 2100);
WIRE 16 -1 (-6625 2000)(-6025 2000);
WIRE 16 -1 (-6625 1900)(-6025 1900);
WIRE 16 -1 (-6625 1800)(-6025 1800);
WIRE 16 -1 (-6625 1700)(-6025 1700);
WIRE 16 -1 (-6625 1600)(-6025 1600);
WIRE 16 -1 (-6625 1500)(-6025 1500);
WIRE 16 -1 (-6625 1400)(-6025 1400);
WIRE 16 -1 (-6475 2150)(-6025 2150);
WIRE 16 -1 (-6475 2050)(-6025 2050);
WIRE 16 -1 (-6475 1950)(-6025 1950);
WIRE 16 -1 (-6475 1850)(-6025 1850);
WIRE 16 -1 (-6475 1750)(-6025 1750);
WIRE 16 -1 (-6475 1650)(-6025 1650);
WIRE 16 -1 (-6475 1550)(-6025 1550);
WIRE 16 -1 (-6475 1450)(-6025 1450);
WIRE 16 -1 (-6475 4175)(-6025 4175);
WIRE 16 -1 (-6475 4275)(-6025 4275);
WIRE 16 -1 (-6475 4375)(-6025 4375);
WIRE 16 -1 (-6475 4475)(-6025 4475);
WIRE 16 -1 (-6475 4575)(-6025 4575);
WIRE 16 -1 (-6475 4675)(-6025 4675);
WIRE 16 -1 (-6475 4775)(-6025 4775);
WIRE 16 -1 (-6475 4875)(-6025 4875);
WIRE 16 -1 (-6475 5075)(-6025 5075);
WIRE 16 -1 (-6475 5175)(-6025 5175);
WIRE 16 -1 (-6475 5275)(-6025 5275);
WIRE 16 -1 (-6475 5375)(-6025 5375);
WIRE 16 -1 (-6475 5475)(-6025 5475);
WIRE 16 -1 (-6475 5575)(-6025 5575);
WIRE 16 -1 (-6475 5675)(-6025 5675);
WIRE 16 -1 (-6625 4125)(-6025 4125);
WIRE 16 -1 (-6625 4225)(-6025 4225);
WIRE 16 -1 (-6625 4325)(-6025 4325);
WIRE 16 -1 (-6625 4425)(-6025 4425);
WIRE 16 -1 (-6625 4525)(-6025 4525);
WIRE 16 -1 (-6625 4625)(-6025 4625);
WIRE 16 -1 (-6625 4725)(-6025 4725);
WIRE 16 -1 (-6625 4825)(-6025 4825);
WIRE 16 -1 (-6625 4925)(-6025 4925);
WIRE 16 -1 (-6625 5025)(-6025 5025);
WIRE 16 -1 (-6625 5125)(-6025 5125);
WIRE 16 -1 (-6625 5225)(-6025 5225);
WIRE 16 -1 (-6625 5325)(-6025 5325);
WIRE 16 -1 (-6625 5425)(-6025 5425);
WIRE 16 -1 (-6625 5525)(-6025 5525);
WIRE 16 -1 (-6625 5625)(-6025 5625);
WIRE 16 -1 (-3150 1450)(-3525 1450);
WIRE 16 -1 (-3525 1950)(-3150 1950);
WIRE 16 -1 (-3525 1850)(-3150 1850);
WIRE 16 -1 (-3525 1750)(-3150 1750);
WIRE 16 -1 (-3525 1650)(-3150 1650);
WIRE 16 -1 (-3525 1550)(-3150 1550);
WIRE 16 -1 (-3525 2000)(-3000 2000);
WIRE 16 -1 (-3525 1900)(-3000 1900);
WIRE 16 -1 (-3525 1800)(-3000 1800);
WIRE 16 -1 (-3525 1700)(-3000 1700);
WIRE 16 -1 (-3525 1600)(-3000 1600);
WIRE 16 -1 (-3525 1500)(-3000 1500);
WIRE 16 -1 (-3000 1400)(-3525 1400);
WIRE 16 -1 (-3525 2250)(-3150 2250);
WIRE 16 -1 (-3525 2350)(-3150 2350);
WIRE 16 -1 (-3525 2450)(-3150 2450);
WIRE 16 -1 (-3525 2550)(-3150 2550);
WIRE 16 -1 (-3525 2150)(-3150 2150);
WIRE 16 -1 (-3525 2050)(-3150 2050);
WIRE 16 -1 (-3525 2650)(-3150 2650);
WIRE 16 -1 (-3525 2750)(-3150 2750);
WIRE 16 -1 (-3525 2850)(-3150 2850);
WIRE 16 -1 (-3525 2950)(-3150 2950);
WIRE 16 -1 (-3525 2200)(-3000 2200);
WIRE 16 -1 (-3525 2300)(-3000 2300);
WIRE 16 -1 (-3525 2400)(-3000 2400);
WIRE 16 -1 (-3525 2500)(-3000 2500);
WIRE 16 -1 (-3525 2600)(-3000 2600);
WIRE 16 -1 (-3525 2700)(-3000 2700);
WIRE 16 -1 (-3525 2800)(-3000 2800);
WIRE 16 -1 (-3525 2900)(-3000 2900);
WIRE 16 -1 (-3525 2100)(-3000 2100);
WIRE 16 -1 (-3525 4175)(-3150 4175);
WIRE 16 -1 (-3525 4275)(-3150 4275);
WIRE 16 -1 (-3525 4375)(-3150 4375);
WIRE 16 -1 (-3525 4475)(-3150 4475);
WIRE 16 -1 (-3525 4575)(-3150 4575);
WIRE 16 -1 (-3525 4675)(-3150 4675);
WIRE 16 -1 (-3525 4775)(-3150 4775);
WIRE 16 -1 (-3525 4875)(-3150 4875);
WIRE 16 -1 (-3525 4975)(-3150 4975);
WIRE 16 -1 (-3525 5075)(-3150 5075);
WIRE 16 -1 (-3525 5175)(-3150 5175);
WIRE 16 -1 (-3525 5275)(-3150 5275);
WIRE 16 -1 (-3525 5375)(-3150 5375);
WIRE 16 -1 (-3525 5475)(-3150 5475);
WIRE 16 -1 (-3525 5575)(-3150 5575);
WIRE 16 -1 (-3525 5675)(-3150 5675);
WIRE 16 -1 (-3525 4125)(-3000 4125);
WIRE 16 -1 (-3525 4225)(-3000 4225);
WIRE 16 -1 (-3525 4325)(-3000 4325);
WIRE 16 -1 (-3525 4425)(-3000 4425);
WIRE 16 -1 (-3525 4525)(-3000 4525);
WIRE 16 -1 (-3525 4625)(-3000 4625);
WIRE 16 -1 (-3525 4725)(-3000 4725);
WIRE 16 -1 (-3525 4825)(-3000 4825);
WIRE 16 -1 (-3525 4925)(-3000 4925);
WIRE 16 -1 (-3525 5025)(-3000 5025);
WIRE 16 -1 (-3525 5125)(-3000 5125);
WIRE 16 -1 (-3525 5225)(-3000 5225);
WIRE 16 -1 (-3525 5325)(-3000 5325);
WIRE 16 -1 (-3525 5425)(-3000 5425);
WIRE 16 -1 (-3525 5525)(-3000 5525);
WIRE 16 -1 (-3525 5625)(-3000 5625);
QUIT
